P  JOB   C:/<user>/worklib/wcs2tbp/physical/x887571-005_osp.brd                    
P  CODE  00                                                                     
P  UNITS CUST 0                                                                 
P  TITLE C:/<user>/worklib/wcs2tbp/physical/x887571-005_osp.brd                    
P  NUM   001                                                                    
P  REV   A                                                                      
P  VER IPC-D-356A                                                               
C                                                                               
C  IPC-D-356 Ouptut File from Allegro                                           
C  IPC File Date: Thu Jul 03 01:11:52 2014                                      
C                                                                               
C                                                                               
C  Board File:             x887571-005_osp.brd                                  
C  Design Rule Status:     UP TO DATE                                           
C  Unit of Measure:        mils                                                 
C  Decimal Place Accuracy: 4                                                    
C  Number of etch Layers:  8                                                    
C  Board Thickness(mils):  62.600000                                            
C  Drawing Extents(mils):  -335688976  -100000000  160000000  140000000         
C                                                                               
C                                                                               
C  BOARD LAYER INFORMATION                                                      
C                                                                               
C     Layer      Layer            Layer             Film  Layer                 
C     Name       Material         Type              Type  Number                
C  ---------------------------------------------------------                    
C  TOP           PLATED_COPPER_F  CONDUCTOR         POS     1                   
C  LYR2          COPPER           PLANE             POS     2                   
C  LYR3          COPPER           CONDUCTOR         POS     3                   
C  LYR4          COPPER           CONDUCTOR         POS     4                   
C  LYR5          COPPER           PLANE             POS     5                   
C  LYR6          COPPER           CONDUCTOR         POS     6                   
C  LYR7          COPPER           PLANE             POS     7                   
C  BOTTOM        PLATED_COPPER_F  CONDUCTOR         POS     8                   
C                                                                               
C                                                                               
C  PADSTACK INFORMATION                                                         
C                                                                               
C     Padstack          First     Last                                          
C     Name              Layer     Layer     Width     Height                    
C  ---------------------------------------------------------                    
C  OB14X71              TOP       TOP          140000    710000                 
C  OB15X79              TOP       TOP          150000    790000                 
C  OB20X79              TOP       TOP          200000    790000                 
C  R50X135              TOP       TOP          500000   1350000                 
C  TP-22-32R10-OSP      TOP       BOTTOM       320000    320000                 
C  FIDUCIAL_40          TOP       TOP         1200000   1200000                 
C  32S20PF              TOP       BOTTOM       320000    320000                 
C  54R40                TOP       BOTTOM       540000    540000                 
C  79S33PF              TOP       BOTTOM       790000    790000                 
C  79S41PF              TOP       BOTTOM       790000    790000                 
C  61R41PF              TOP       BOTTOM       610000    610000                 
C  50D125NP_TOOL        TOP       BOTTOM      1450000   1450000                 
C  276R138              TOP       BOTTOM      2760000   2760000                 
C  50D61NP              TOP       BOTTOM       810000    810000                 
C  50D63NP              TOP       BOTTOM       830000    830000                 
C  58R38                TOP       BOTTOM       580000    580000                 
C  150R87               TOP       BOTTOM      1500000   1500000                 
C  44R24                TOP       BOTTOM       440000    440000                 
C  27R15PF              TOP       BOTTOM       270000    270000                 
C  220R156              TOP       BOTTOM      2200000   2200000                 
C  50D156NP             TOP       BOTTOM      1760000   1760000                 
C  32R20PF              TOP       BOTTOM       320000    320000                 
C  50D86NP              TOP       BOTTOM      1060000   1060000                 
C  54R30                TOP       BOTTOM       540000    540000                 
C  54S30                TOP       BOTTOM       540000    540000                 
C  20D50NP              TOP       BOTTOM       700000    700000                 
C  79R55                TOP       BOTTOM       790000    790000                 
C  79S55                TOP       BOTTOM       790000    790000                 
C  26R14_22-NO-TSM      TOP       BOTTOM       260000    260000                 
C  VIA-20R10            TOP       BOTTOM       200000    200000                 
C  VIA-22R10            TOP       BOTTOM       220000    220000                 
C  TP-22-32R10-SI       TOP       BOTTOM       320000    320000                 
C  R14X71               TOP       TOP          140000    710000                 
C  R20X79               TOP       TOP          200000    790000                 
C  R32X197_BOT          BOTTOM    BOTTOM       320000   1970000                 
C  R32X197_TOP          TOP       TOP          320000   1970000                 
C  R372X248_TOP         TOP       TOP         3720000   2480000                 
C  R372X248_BOT         BOTTOM    BOTTOM      3720000   2480000                 
C  R28X32               TOP       TOP          280000    320000                 
C  R20X23               TOP       TOP          200000    230000                 
C  25R                  TOP       TOP          250000    250000                 
C  TP-32R-BOT-SI        BOTTOM    BOTTOM       320000    320000                 
C  TP-4X12-15X15-BMP    TOP       TOP           40000    120000                 
C                                                                               
C                                                                               
C  ****************************************                                     
C     Name mapping for long Signal names                                        
C  ****************************************                                     
C                                                                               
P  NNAMEm0000 BLADE_MATED_B2_N<0>                                               
P  NNAMEm0001 BLADE_MATED_B1_N<0>                                               
P  NNAMEm0002 UNNAMED_8_FERRITE_I54_A                                           
P  NNAMEm0003 UNNAMED_8_FERRITE_I51_A                                           
P  NNAMEm0004 UNNAMED_8_FERRITE_I47_B                                           
P  NNAMEm0005 UNNAMED_6_FERRITE_I27_B                                           
P  NNAMEm0006 UNNAMED_6_FERRITE_I24_A                                           
P  NNAMEm0007 UNNAMED_6_1X2HDR_I56_IO                                           
P  NNAMEm0008 UNNAMED_6_1X2HDR_I52_IO                                           
P  NNAMEm0009 UNNAMED_4_FERRITE_I151_B                                          
P  NNAMEm0010 UNNAMED_4_FERRITE_I148_A                                          
P  NNAMEm0011 UNNAMED_4_1X2HDR_I90_IO                                           
P  NNAMEm0012 UNNAMED_4_1X2HDR_I81_IO                                           
P  NNAMEm0013 UNNAMED_16_FERRITE_I46_B                                          
P  NNAMEm0014 UNNAMED_16_FERRITE_I40_A                                          
P  NNAMEm0015 UNNAMED_16_FERRITE_I115_A                                         
P  NNAMEm0016 PCIE_T2B_B2_RX_DP<9>                                              
P  NNAMEm0017 PCIE_T2B_B2_RX_DP<8>                                              
P  NNAMEm0018 PCIE_T2B_B2_RX_DP<7>                                              
P  NNAMEm0019 PCIE_T2B_B2_RX_DP<6>                                              
P  NNAMEm0020 PCIE_T2B_B2_RX_DP<5>                                              
P  NNAMEm0021 PCIE_T2B_B2_RX_DP<4>                                              
P  NNAMEm0022 PCIE_T2B_B2_RX_DP<3>                                              
P  NNAMEm0023 PCIE_T2B_B2_RX_DP<2>                                              
P  NNAMEm0024 PCIE_T2B_B2_RX_DP<1>                                              
P  NNAMEm0025 PCIE_T2B_B2_RX_DP<15>                                             
P  NNAMEm0026 PCIE_T2B_B2_RX_DP<14>                                             
P  NNAMEm0027 PCIE_T2B_B2_RX_DP<13>                                             
P  NNAMEm0028 PCIE_T2B_B2_RX_DP<12>                                             
P  NNAMEm0029 PCIE_T2B_B2_RX_DP<11>                                             
P  NNAMEm0030 PCIE_T2B_B2_RX_DP<10>                                             
P  NNAMEm0031 PCIE_T2B_B2_RX_DP<0>                                              
P  NNAMEm0032 PCIE_T2B_B2_RX_DN<9>                                              
P  NNAMEm0033 PCIE_T2B_B2_RX_DN<8>                                              
P  NNAMEm0034 PCIE_T2B_B2_RX_DN<7>                                              
P  NNAMEm0035 PCIE_T2B_B2_RX_DN<6>                                              
P  NNAMEm0036 PCIE_T2B_B2_RX_DN<5>                                              
P  NNAMEm0037 PCIE_T2B_B2_RX_DN<4>                                              
P  NNAMEm0038 PCIE_T2B_B2_RX_DN<3>                                              
P  NNAMEm0039 PCIE_T2B_B2_RX_DN<2>                                              
P  NNAMEm0040 PCIE_T2B_B2_RX_DN<1>                                              
P  NNAMEm0041 PCIE_T2B_B2_RX_DN<15>                                             
P  NNAMEm0042 PCIE_T2B_B2_RX_DN<14>                                             
P  NNAMEm0043 PCIE_T2B_B2_RX_DN<13>                                             
P  NNAMEm0044 PCIE_T2B_B2_RX_DN<12>                                             
P  NNAMEm0045 PCIE_T2B_B2_RX_DN<11>                                             
P  NNAMEm0046 PCIE_T2B_B2_RX_DN<10>                                             
P  NNAMEm0047 PCIE_T2B_B2_RX_DN<0>                                              
P  NNAMEm0048 PCIE_T2B_B1_RX_DP<9>                                              
P  NNAMEm0049 PCIE_T2B_B1_RX_DP<8>                                              
P  NNAMEm0050 PCIE_T2B_B1_RX_DP<7>                                              
P  NNAMEm0051 PCIE_T2B_B1_RX_DP<6>                                              
P  NNAMEm0052 PCIE_T2B_B1_RX_DP<5>                                              
P  NNAMEm0053 PCIE_T2B_B1_RX_DP<4>                                              
P  NNAMEm0054 PCIE_T2B_B1_RX_DP<3>                                              
P  NNAMEm0055 PCIE_T2B_B1_RX_DP<2>                                              
P  NNAMEm0056 PCIE_T2B_B1_RX_DP<1>                                              
P  NNAMEm0057 PCIE_T2B_B1_RX_DP<15>                                             
P  NNAMEm0058 PCIE_T2B_B1_RX_DP<14>                                             
P  NNAMEm0059 PCIE_T2B_B1_RX_DP<13>                                             
P  NNAMEm0060 PCIE_T2B_B1_RX_DP<12>                                             
P  NNAMEm0061 PCIE_T2B_B1_RX_DP<11>                                             
P  NNAMEm0062 PCIE_T2B_B1_RX_DP<10>                                             
P  NNAMEm0063 PCIE_T2B_B1_RX_DP<0>                                              
P  NNAMEm0064 PCIE_T2B_B1_RX_DN<9>                                              
P  NNAMEm0065 PCIE_T2B_B1_RX_DN<8>                                              
P  NNAMEm0066 PCIE_T2B_B1_RX_DN<7>                                              
P  NNAMEm0067 PCIE_T2B_B1_RX_DN<6>                                              
P  NNAMEm0068 PCIE_T2B_B1_RX_DN<5>                                              
P  NNAMEm0069 PCIE_T2B_B1_RX_DN<4>                                              
P  NNAMEm0070 PCIE_T2B_B1_RX_DN<3>                                              
P  NNAMEm0071 PCIE_T2B_B1_RX_DN<2>                                              
P  NNAMEm0072 PCIE_T2B_B1_RX_DN<1>                                              
P  NNAMEm0073 PCIE_T2B_B1_RX_DN<15>                                             
P  NNAMEm0074 PCIE_T2B_B1_RX_DN<14>                                             
P  NNAMEm0075 PCIE_T2B_B1_RX_DN<13>                                             
P  NNAMEm0076 PCIE_T2B_B1_RX_DN<12>                                             
P  NNAMEm0077 PCIE_T2B_B1_RX_DN<11>                                             
P  NNAMEm0078 PCIE_T2B_B1_RX_DN<10>                                             
P  NNAMEm0079 PCIE_T2B_B1_RX_DN<0>                                              
P  NNAMEm0080 PCIE_RESET_B2_N<3>                                                
P  NNAMEm0081 PCIE_RESET_B2_N<2>                                                
P  NNAMEm0082 PCIE_RESET_B2_N<1>                                                
P  NNAMEm0083 PCIE_RESET_B2_N<0>                                                
P  NNAMEm0084 PCIE_RESET_B1_N<3>                                                
P  NNAMEm0085 PCIE_RESET_B1_N<2>                                                
P  NNAMEm0086 PCIE_RESET_B1_N<1>                                                
P  NNAMEm0087 PCIE_RESET_B1_N<0>                                                
P  NNAMEm0088 PCIE_CFG_B2_ID1                                                   
P  NNAMEm0089 PCIE_CFG_B2_ID0                                                   
P  NNAMEm0090 PCIE_CFG_B1_ID1                                                   
P  NNAMEm0091 PCIE_CFG_B1_ID0                                                   
P  NNAMEm0092 PCIE_B2T_B2_TX_DP<9>                                              
P  NNAMEm0093 PCIE_B2T_B2_TX_DP<8>                                              
P  NNAMEm0094 PCIE_B2T_B2_TX_DP<7>                                              
P  NNAMEm0095 PCIE_B2T_B2_TX_DP<6>                                              
P  NNAMEm0096 PCIE_B2T_B2_TX_DP<5>                                              
P  NNAMEm0097 PCIE_B2T_B2_TX_DP<4>                                              
P  NNAMEm0098 PCIE_B2T_B2_TX_DP<3>                                              
P  NNAMEm0099 PCIE_B2T_B2_TX_DP<2>                                              
P  NNAMEm0100 PCIE_B2T_B2_TX_DP<1>                                              
P  NNAMEm0101 PCIE_B2T_B2_TX_DP<15>                                             
P  NNAMEm0102 PCIE_B2T_B2_TX_DP<14>                                             
P  NNAMEm0103 PCIE_B2T_B2_TX_DP<13>                                             
P  NNAMEm0104 PCIE_B2T_B2_TX_DP<12>                                             
P  NNAMEm0105 PCIE_B2T_B2_TX_DP<11>                                             
P  NNAMEm0106 PCIE_B2T_B2_TX_DP<10>                                             
P  NNAMEm0107 PCIE_B2T_B2_TX_DP<0>                                              
P  NNAMEm0108 PCIE_B2T_B2_TX_DN<9>                                              
P  NNAMEm0109 PCIE_B2T_B2_TX_DN<8>                                              
P  NNAMEm0110 PCIE_B2T_B2_TX_DN<7>                                              
P  NNAMEm0111 PCIE_B2T_B2_TX_DN<6>                                              
P  NNAMEm0112 PCIE_B2T_B2_TX_DN<5>                                              
P  NNAMEm0113 PCIE_B2T_B2_TX_DN<4>                                              
P  NNAMEm0114 PCIE_B2T_B2_TX_DN<3>                                              
P  NNAMEm0115 PCIE_B2T_B2_TX_DN<2>                                              
P  NNAMEm0116 PCIE_B2T_B2_TX_DN<1>                                              
P  NNAMEm0117 PCIE_B2T_B2_TX_DN<15>                                             
P  NNAMEm0118 PCIE_B2T_B2_TX_DN<14>                                             
P  NNAMEm0119 PCIE_B2T_B2_TX_DN<13>                                             
P  NNAMEm0120 PCIE_B2T_B2_TX_DN<12>                                             
P  NNAMEm0121 PCIE_B2T_B2_TX_DN<11>                                             
P  NNAMEm0122 PCIE_B2T_B2_TX_DN<10>                                             
P  NNAMEm0123 PCIE_B2T_B2_TX_DN<0>                                              
P  NNAMEm0124 PCIE_B2T_B1_TX_DP<9>                                              
P  NNAMEm0125 PCIE_B2T_B1_TX_DP<8>                                              
P  NNAMEm0126 PCIE_B2T_B1_TX_DP<7>                                              
P  NNAMEm0127 PCIE_B2T_B1_TX_DP<6>                                              
P  NNAMEm0128 PCIE_B2T_B1_TX_DP<5>                                              
P  NNAMEm0129 PCIE_B2T_B1_TX_DP<4>                                              
P  NNAMEm0130 PCIE_B2T_B1_TX_DP<3>                                              
P  NNAMEm0131 PCIE_B2T_B1_TX_DP<2>                                              
P  NNAMEm0132 PCIE_B2T_B1_TX_DP<1>                                              
P  NNAMEm0133 PCIE_B2T_B1_TX_DP<15>                                             
P  NNAMEm0134 PCIE_B2T_B1_TX_DP<14>                                             
P  NNAMEm0135 PCIE_B2T_B1_TX_DP<13>                                             
P  NNAMEm0136 PCIE_B2T_B1_TX_DP<12>                                             
P  NNAMEm0137 PCIE_B2T_B1_TX_DP<11>                                             
P  NNAMEm0138 PCIE_B2T_B1_TX_DP<10>                                             
P  NNAMEm0139 PCIE_B2T_B1_TX_DP<0>                                              
P  NNAMEm0140 PCIE_B2T_B1_TX_DN<9>                                              
P  NNAMEm0141 PCIE_B2T_B1_TX_DN<8>                                              
P  NNAMEm0142 PCIE_B2T_B1_TX_DN<7>                                              
P  NNAMEm0143 PCIE_B2T_B1_TX_DN<6>                                              
P  NNAMEm0144 PCIE_B2T_B1_TX_DN<5>                                              
P  NNAMEm0145 PCIE_B2T_B1_TX_DN<4>                                              
P  NNAMEm0146 PCIE_B2T_B1_TX_DN<3>                                              
P  NNAMEm0147 PCIE_B2T_B1_TX_DN<2>                                              
P  NNAMEm0148 PCIE_B2T_B1_TX_DN<1>                                              
P  NNAMEm0149 PCIE_B2T_B1_TX_DN<15>                                             
P  NNAMEm0150 PCIE_B2T_B1_TX_DN<14>                                             
P  NNAMEm0151 PCIE_B2T_B1_TX_DN<13>                                             
P  NNAMEm0152 PCIE_B2T_B1_TX_DN<12>                                             
P  NNAMEm0153 PCIE_B2T_B1_TX_DN<11>                                             
P  NNAMEm0154 PCIE_B2T_B1_TX_DN<10>                                             
P  NNAMEm0155 PCIE_B2T_B1_TX_DN<0>                                              
P  NNAMEm0156 P3V3_40G_B2_VCC_TX                                                
P  NNAMEm0157 P3V3_40G_B2_VCC_RX                                                
P  NNAMEm0158 P3V3_40G_B2_VCC1                                                  
P  NNAMEm0159 P3V3_40G_B1_VCC_TX                                                
P  NNAMEm0160 P3V3_40G_B1_VCC_RX                                                
P  NNAMEm0161 P3V3_40G_B1_VCC1                                                  
P  NNAMEm0162 P3V3_10G_B2_VCCT                                                  
P  NNAMEm0163 P3V3_10G_B2_VCCR                                                  
P  NNAMEm0164 P3V3_10G_B1_VCCT                                                  
P  NNAMEm0165 P3V3_10G_B1_VCCR                                                  
P  NNAMEm0166 MEZZ_PRESENT_B2_N                                                 
P  NNAMEm0167 MEZZ_PRESENT_B1_N                                                 
P  NNAMEm0168 JBOD_B2_MATED_N                                                   
P  NNAMEm0169 JBOD_B1_MATED_N                                                   
P  NNAMEm0170 ETH40G_B2_RESET_N                                                 
P  NNAMEm0171 ETH40G_B2_PRES_N                                                  
P  NNAMEm0172 ETH40G_B2_MODSEL_N                                                
P  NNAMEm0173 ETH40G_B2_MODPRS_N                                                
P  NNAMEm0174 ETH40G_B2_LPMODE                                                  
P  NNAMEm0175 ETH40G_B2_INT_N                                                   
P  NNAMEm0176 ETH40G_B1_RESET_N                                                 
P  NNAMEm0177 ETH40G_B1_PRES_N                                                  
P  NNAMEm0178 ETH40G_B1_MODSEL_N                                                
P  NNAMEm0179 ETH40G_B1_MODPRS_N                                                
P  NNAMEm0180 ETH40G_B1_LPMODE                                                  
P  NNAMEm0181 ETH40G_B1_INT_N                                                   
P  NNAMEm0182 ETH10G_B2_TX_FAULT                                                
P  NNAMEm0183 ETH10G_B2_TX_DIS                                                  
P  NNAMEm0184 ETH10G_B2_RX_LOS                                                  
P  NNAMEm0185 ETH10G_B2_PRES_N                                                  
P  NNAMEm0186 ETH10G_B2_MOD_ABS                                                 
P  NNAMEm0187 ETH10G_B1_TX_FAULT                                                
P  NNAMEm0188 ETH10G_B1_TX_DIS                                                  
P  NNAMEm0189 ETH10G_B1_RX_LOS                                                  
P  NNAMEm0190 ETH10G_B1_PRES_N                                                  
P  NNAMEm0191 ETH10G_B1_MOD_ABS                                                 
P  NNAMEm0192 CLK_100M_B2_P<3>                                                  
P  NNAMEm0193 CLK_100M_B2_P<2>                                                  
P  NNAMEm0194 CLK_100M_B2_P<1>                                                  
P  NNAMEm0195 CLK_100M_B2_P<0>                                                  
P  NNAMEm0196 CLK_100M_B2_N<3>                                                  
P  NNAMEm0197 CLK_100M_B2_N<2>                                                  
P  NNAMEm0198 CLK_100M_B2_N<1>                                                  
P  NNAMEm0199 CLK_100M_B2_N<0>                                                  
P  NNAMEm0200 CLK_100M_B1_P<3>                                                  
P  NNAMEm0201 CLK_100M_B1_P<2>                                                  
P  NNAMEm0202 CLK_100M_B1_P<1>                                                  
P  NNAMEm0203 CLK_100M_B1_P<0>                                                  
P  NNAMEm0204 CLK_100M_B1_N<3>                                                  
P  NNAMEm0205 CLK_100M_B1_N<2>                                                  
P  NNAMEm0206 CLK_100M_B1_N<1>                                                  
P  NNAMEm0207 CLK_100M_B1_N<0>                                                  
P  NNAMEm0208 BLADE_B2_MATED_N                                                  
P  NNAMEm0209 BLADE_B1_MATED_N<1>                                               
C                                                                               
C  ****************************************                                     
C      SIGNAL PINS & VIAS ON THE BOARD                                          
C  ****************************************                                     
C                                                                               
317SERIAL_B2_TX2    J13   -H8   D0200PA00X-073016Y-014000X0320Y    R180 S3      
317SERIAL_B2_TX2    J19   -H4   D0200PA00X-031118Y-014039X0320Y    R180 S3      
327SERIAL_B2_TX2    U1    -S8         A08X-164949Y+000724X0320Y1970R180 S2      
317SERIAL_B2_TX2    VIA   -    MD0100PA00X-031650Y-011350X0220Y         S0      
317SERIAL_B2_TX2    VIA   -    MD0100PA00X-164949Y-002740X0220Y         S0      
317SERIAL_B2_TX2    VIA   -    MD0100PA00X-144880Y-006770X0220Y         S0      
327SERIAL_B2_TX1    U1    -S12        A08X-162949Y+000724X0320Y1970R180 S2      
317SERIAL_B2_TX1    VIA   -    MD0100PA00X-029640Y-011350X0220Y         S0      
317SERIAL_B2_TX1    J19   -H3   D0200PA00X-030331Y-014000X0320Y    R180 S3      
317SERIAL_B2_TX1    VIA   -    MD0100PA00X-015240Y-012505X0220Y         S0      
317SERIAL_B2_TX1    J23   -A3   D0200PA00X-012079Y-017858X0320Y    R180 S3      
317SERIAL_B2_TX1    VIA   -    MD0100PA00X-162949Y-002770X0220Y         S0      
317SERIAL_B2_TX1    VIA   -    MD0100PA00X-144870Y-005990X0220Y         S0      
327SERIAL_B2_RX2    U1    -S7         A08X-165449Y+000724X0320Y1970R180 S2      
317SERIAL_B2_RX2    J19   -G4   D0200PA00X-031118Y-014591X0320Y    R180 S3      
317SERIAL_B2_RX2    VIA   -    MD0100PA00X-032160Y-011350X0220Y         S0      
317SERIAL_B2_RX2    J13   -I8   D0200PA00X-073016Y-013449X0320Y    R180 S3      
317SERIAL_B2_RX2    VIA   -    MD0100PA00X-059120Y-017970X0220Y         S0      
317SERIAL_B2_RX2    VIA   -    MD0100PA00X-165449Y-002730X0220Y         S0      
317SERIAL_B2_RX2    VIA   -    MD0100PA00X-145180Y-006960X0220Y         S0      
327SERIAL_B2_RX1    U1    -S11        A08X-163449Y+000724X0320Y1970R180 S2      
317SERIAL_B2_RX1    J19   -G3   D0200PA00X-030331Y-014551X0320Y    R180 S3      
317SERIAL_B2_RX1    J23   -B3   D0200PA00X-012079Y-017307X0320Y    R180 S3      
317SERIAL_B2_RX1    VIA   -    MD0100PA00X-015090Y-012110X0220Y         S0      
317SERIAL_B2_RX1    VIA   -    MD0100PA00X-163449Y-002760X0220Y         S0      
317SERIAL_B2_RX1    VIA   -    MD0100PA00X-145150Y-006180X0220Y         S0      
317SERIAL_B1_TX2    VIA   -    MD0100PA00X-144900Y-008030X0220Y         S0      
327SERIAL_B1_TX2    U1    -S5         A01X-164949Y+000724X0320Y1970R180 S1      
317SERIAL_B1_TX2    VIA   -    MD0100PA00X-162160Y-006940X0220Y         S0      
317SERIAL_B1_TX2    J1    -H8   D0200PA00X-160024Y-014000X0320Y    R180 S3      
317SERIAL_B1_TX2    J7    -H4   D0200PA00X-118126Y-014039X0320Y    R180 S3      
317SERIAL_B1_TX2    VIA   -    MD0100PA00X-117030Y-011460X0220Y         S0      
317SERIAL_B1_RX2    VIA   -    MD0100PA00X-161840Y-007160X0220Y         S0      
317SERIAL_B1_RX2    VIA   -    MD0100PA00X-145210Y-008220X0220Y         S0      
317SERIAL_B1_RX2    J1    -I8   D0200PA00X-160024Y-013449X0320Y    R180 S3      
317SERIAL_B1_RX2    J7    -G4   D0200PA00X-118126Y-014591X0320Y    R180 S3      
317SERIAL_B1_RX2    VIA   -    MD0100PA00X-117610Y-011480X0220Y         S0      
327SERIAL_B1_RX2    U1    -S6         A01X-165449Y+000724X0320Y1970R180 S1      
327PSU_B2_ALERT_N   U1    -S9         A08X-164449Y+000724X0320Y1970R180 S2      
317PSU_B2_ALERT_N   VIA   -    MD0100PA00X-037480Y-010570X0220Y         S0      
317PSU_B2_ALERT_N   VIA   -    MD0100PA00X-031210Y-011350X0220Y         S0      
317PSU_B2_ALERT_N   J19   -G5   D0200PA00X-031906Y-014551X0320Y    R180 S3      
317PSU_B2_ALERT_N   J13   -H7   D0200PA00X-072228Y-013961X0320Y    R180 S3      
327PSU_B2_ALERT_N   J29   -1          A01X-046027Y-000600X0500Y1350R270 S1      
317PSU_B2_ALERT_N   VIA   -    MD0100PA00X-044860Y-000590X0220Y         S0      
317PSU_B2_ALERT_N   VIA   -    MD0100PA00X-164449Y-002750X0220Y         S0      
317PSU_B2_ALERT_N   VIA   -    MD0100PA00X-145170Y-006570X0220Y         S0      
317BLADE_B2_EN1     VIA   -    MD0100PA00X-043677Y-009240X0220Y         S0      
317BLADE_B2_EN1     VIA   -    MD0100PA00X-043212Y-008708X0220Y         S0      
327BLADE_B2_EN1     U1    -S10        A08X-163949Y+000724X0320Y1970R180 S2      
317BLADE_B2_EN1     VIA   -    MD0100PA00X-042460Y-001440X0220Y         S0      
317BLADE_B2_EN1     J19   -H2   D0200PA00X-029543Y-014039X0320Y    R180 S3      
317BLADE_B2_EN1     VIA   -    MD0100PA00X-028650Y-011370X0220Y         S0      
317BLADE_B2_EN1     J23   -C4   D0200PA00X-012866Y-016795X0320Y    R180 S3      
317BLADE_B2_EN1     VIA   -    MD0100PA00X-016376Y-012858X0220Y         S0      
327BLADE_B2_EN1     J28   -1          A01X-042947Y-000690X0500Y1350R270 S1      
317BLADE_B2_EN1     VIA   -    MD0100PA00X-163949Y-002750X0220Y         S0      
317BLADE_B2_EN1     VIA   -    MD0100PA00X-144880Y-006380X0220Y         S0      
317PSU_B1_ALERT_N   J1    -H7   D0200PA00X-159236Y-013961X0320Y    R180 S3      
317PSU_B1_ALERT_N   VIA   -    MD0100PA00X-132100Y-009485X0220Y         S0      
317PSU_B1_ALERT_N   VIA   -    MD0100PA00X-145200Y-007820X0220Y         S0      
327PSU_B1_ALERT_N   U1    -S4         A01X-164449Y+000724X0320Y1970R180 S1      
317PSU_B1_ALERT_N   VIA   -    MD0100PA00X-161850Y-006720X0220Y         S0      
317PSU_B1_ALERT_N   J7    -G5   D0200PA00X-118913Y-014551X0320Y    R180 S3      
317PSU_B1_ALERT_N   VIA   -    MD0100PA00X-120210Y-010320X0220Y         S0      
327PSU_B1_ALERT_N   J26   -1          A01X-133035Y-000600X0500Y1350R270 S1      
317PSU_B1_ALERT_N   VIA   -    MD0100PA00X-131850Y-000600X0220Y         S0      
317BLADE_B1_EN1     J7    -H2   D0200PA00X-116551Y-014039X0320Y    R180 S3      
317BLADE_B1_EN1     VIA   -    MD0100PA00X-115440Y-010790X0220Y         S0      
317BLADE_B1_EN1     VIA   -    MD0100PA00X-130035Y-008850X0220Y         S0      
317BLADE_B1_EN1     VIA   -    MD0100PA00X-103384Y-012858X0220Y         S0      
317BLADE_B1_EN1     VIA   -    MD0100PA00X-144890Y-007610X0220Y         S0      
317BLADE_B1_EN1     VIA   -    MD0100PA00X-130685Y-009500X0220Y         S0      
317BLADE_B1_EN1     J11   -C4   D0200PA00X-099874Y-016795X0320Y    R180 S3      
327BLADE_B1_EN1     U1    -S3         A01X-163949Y+000724X0320Y1970R180 S1      
327BLADE_B1_EN1     J25   -1          A01X-129955Y-000690X0500Y1350R270 S1      
317BLADE_B1_EN1     VIA   -    MD0100PA00X-129540Y-001340X0220Y         S0      
317BLADE_B1_EN1     VIA   -    MD0100PA00X-162160Y-006510X0220Y         S0      
317P5V_USB_B2       J13   -E10  D0200PA00X-074591Y-015654X0320Y    R180 S3      
317P5V_USB_B2       U3    -1   MD0400PA00X-079373Y-016185X0540Y    R090 S3      
317P5V_USB_B1       U2    -1   MD0400PA00X-164900Y-012150X0540Y    R090 S3      
317P5V_USB_B1       J1    -E10  D0200PA00X-161598Y-015654X0320Y    R180 S3      
317USB_B2_P         U3    -3    D0400PA00X-079373Y-014610X0540Y    R090 S3      
317USB_B2_P         J13   -B10  D0200PA00X-074591Y-017307X0320Y    R180 S3      
317USB_B2_N         U3    -2    D0400PA00X-079373Y-015398X0540Y    R090 S3      
317USB_B2_N         J13   -C10  D0200PA00X-074591Y-016756X0320Y    R180 S3      
317USB_B1_P         J1    -B10  D0200PA00X-161598Y-017307X0320Y    R180 S3      
317USB_B1_P         U2    -3    D0400PA00X-164900Y-010575X0540Y    R090 S3      
317USB_B1_N         J1    -C10  D0200PA00X-161598Y-016756X0320Y    R180 S3      
317USB_B1_N         U2    -2    D0400PA00X-164900Y-011363X0540Y    R090 S3      
317m0000            J13   -I6   D0200PA00X-071441Y-013449X0320Y    R180 S3      
327m0000            R86   -2          A01X-064970Y-012024X0280Y0320R270 S1      
317m0000            VIA   -    MD0100PA00X-064970Y-011720X0220Y         S0      
317m0001            J1    -I6   D0200PA00X-158449Y-013449X0320Y    R180 S3      
327m0001            R85   -2          A01X-151900Y-012024X0280Y0320R270 S1      
317m0001            VIA   -    MD0100PA00X-153000Y-012030X0220Y         S0      
327m0002            FS6   -2          A01X-017519Y+000100X0200Y0230R090 S1      
327m0002            FB6   -1          A01X-017520Y-000450X0200Y0230R270 S1      
317m0002            VIA   -    M      A01X-017510Y-000180X0220Y         S2      
017m0002            VIA   -    M      A08X-017510Y-000180X0320Y         S2      
017m0002                  -    MD0100PA00X-017510Y-000180                       
327m0003            FB5   -1          A01X-017635Y-002985X0200Y0230R270 S1      
317m0003            VIA   -    M      A01X-017635Y-002720X0220Y         S2      
017m0003            VIA   -    M      A08X-017635Y-002720X0320Y         S2      
017m0003                  -    MD0100PA00X-017635Y-002720                       
327m0003            FS5   -2          A01X-017639Y-002450X0200Y0230R090 S1      
327m0004            FS7   -1          A01X-017715Y-004354X0200Y0230     S1      
327m0004            FB7   -2          A01X-018265Y-004355X0200Y0230R180 S1      
317m0004            VIA   -           A01X-017980Y-004350X0220Y         S2      
017m0004            VIA   -           A08X-017980Y-004350X0320Y         S2      
017m0004                  -     D0100PA00X-017980Y-004350                       
327m0005            FS4   -1          A01X-022201Y-017990X0200Y0230R090 S1      
327m0005            FB4   -2          A01X-022895Y-017965X0200Y0230R090 S1      
317m0005            VIA   -           A01X-022540Y-017980X0220Y         S2      
017m0005            VIA   -           A08X-022540Y-017980X0320Y         S2      
017m0005                  -     D0100PA00X-022540Y-017980                       
327m0006            FS3   -2          A01X-025789Y-018000X0200Y0230R090 S1      
317m0006            VIA   -    M      A01X-025480Y-018000X0220Y         S2      
017m0006            VIA   -    M      A08X-025480Y-018000X0320Y         S2      
017m0006                  -    MD0100PA00X-025480Y-018000                       
327m0006            FB3   -1          A01X-025170Y-018000X0200Y0230R090 S1      
327m0007            J29   -2          A01X-047177Y-001600X0500Y1350R270 S1      
327m0007            R39   -1          A01X-048642Y-001604X0280Y0320R270 S1      
327m0008            J28   -2          A01X-044097Y-001690X0500Y1350R270 S1      
327m0008            R37   -1          A01X-045442Y-001684X0280Y0320R270 S1      
327m0009            FB2   -2          A01X-109903Y-017965X0200Y0230R090 S1      
317m0009            VIA   -    M      A01X-109560Y-017960X0220Y         S2      
017m0009            VIA   -    M      A08X-109560Y-017960X0320Y         S2      
017m0009                  -    MD0100PA00X-109560Y-017960                       
327m0009            FS2   -1          A01X-109211Y-017970X0200Y0230R090 S1      
327m0010            FS1   -2          A01X-112769Y-017990X0200Y0230R090 S1      
317m0010            VIA   -    M      A01X-112470Y-018000X0220Y         S2      
017m0010            VIA   -    M      A08X-112470Y-018000X0320Y         S2      
017m0010                  -    MD0100PA00X-112470Y-018000                       
327m0010            FB1   -1          A01X-112180Y-018000X0200Y0230R090 S1      
327m0011            J26   -2          A01X-134185Y-001600X0500Y1350R270 S1      
327m0011            R11   -1          A01X-135650Y-001604X0280Y0320R270 S1      
327m0012            J25   -2          A01X-131105Y-001690X0500Y1350R270 S1      
327m0012            R9    -1          A01X-132450Y-001684X0280Y0320R270 S1      
327m0013            FB10  -2          A01X-105423Y-004405X0200Y0230R180 S1      
317m0013            VIA   -    M      A01X-105120Y-004410X0220Y         S2      
017m0013            VIA   -    M      A08X-105120Y-004410X0320Y         S2      
017m0013                  -    MD0100PA00X-105120Y-004410                       
327m0013            FS10  -1          A01X-104800Y-004399X0200Y0230     S1      
327m0014            FS9   -2          A01X-104719Y+000000X0200Y0230R090 S1      
317m0014            VIA   -    M      A01X-104730Y-000270X0220Y         S2      
017m0014            VIA   -    M      A08X-104730Y-000270X0320Y         S2      
017m0014                  -    MD0100PA00X-104730Y-000270                       
327m0014            FB9   -1          A01X-104720Y-000540X0200Y0230R270 S1      
327m0015            FB8   -1          A01X-104720Y-002940X0200Y0230R270 S1      
317m0015            VIA   -    M      A01X-104729Y-002630X0220Y         S2      
017m0015            VIA   -    M      A08X-104729Y-002630X0320Y         S2      
017m0015                  -    MD0100PA00X-104729Y-002630                       
327m0015            FS8   -2          A01X-104729Y-002300X0200Y0230R090 S1      
317SKU_B2_ID2       VIA   -    MD0100PA00X-028230Y-011370X0220Y         S0      
327SKU_B2_ID2       R34   -2   M      A01X-043384Y-007410X0280Y0320R180 S1      
327SKU_B2_ID2       R61   -1          A01X-043384Y-006860X0280Y0320R180 S1      
327SKU_B2_ID2       R35   -1   M      A01X-043384Y-007960X0280Y0320R180 S1      
317SKU_B2_ID2       VIA   -    MD0100PA00X-042990Y-007960X0220Y         S0      
317SKU_B2_ID2       J19   -F2   D0200PA00X-029543Y-015142X0320Y    R180 S3      
317SKU_B2_ID1       J19   -I4   D0200PA00X-031118Y-013488X0320Y    R180 S3      
317SKU_B2_ID1       VIA   -    MD0100PA00X-030850Y-003640X0220Y         S0      
327SKU_B2_ID1       R33   -1   M      A01X-031274Y-003640X0280Y0320R180 S1      
327SKU_B2_ID1       R32   -2          A01X-031274Y-003090X0280Y0320R180 S1      
317SKU_B2_ID0       J19   -F3   D0200PA00X-030331Y-015102X0320Y    R180 S3      
317SKU_B2_ID0       VIA   -    MD0100PA00X-030940Y-002510X0220Y         S0      
327SKU_B2_ID0       R30   -2   M      A01X-031287Y-002495X0280Y0320R180 S1      
327SKU_B2_ID0       R31   -1          A01X-031287Y-001975X0280Y0320R180 S1      
317SKU_B1_ID2       VIA   -    MD0100PA00X-130240Y-008410X0220Y         S0      
327SKU_B1_ID2       R7    -1   M      A01X-130244Y-007970X0280Y0320R180 S1      
327SKU_B1_ID2       R75   -1          A01X-130244Y-006870X0280Y0320R180 S1      
327SKU_B1_ID2       R6    -2   M      A01X-130244Y-007420X0280Y0320R180 S1      
317SKU_B1_ID2       J7    -F2   D0200PA00X-116551Y-015142X0320Y    R180 S3      
317SKU_B1_ID2       VIA   -    MD0100PA00X-115420Y-010310X0220Y         S0      
317SKU_B1_ID1       J7    -I4   D0200PA00X-118126Y-013488X0320Y    R180 S3      
327SKU_B1_ID1       R5    -1   M      A01X-118224Y-003490X0280Y0320R180 S1      
327SKU_B1_ID1       R4    -2          A01X-118224Y-002940X0280Y0320R180 S1      
317SKU_B1_ID1       VIA   -    MD0100PA00X-117880Y-003480X0220Y         S0      
317SKU_B1_ID0       J7    -F3   D0200PA00X-117339Y-015102X0320Y    R180 S3      
327SKU_B1_ID0       R3    -1   M      A01X-116856Y-003850X0280Y0320     S1      
327SKU_B1_ID0       R2    -2          A01X-116856Y-003300X0280Y0320     S1      
317SKU_B1_ID0       VIA   -    MD0100PA00X-117250Y-003850X0220Y         S0      
317SAS_B2_TX8P      J23   -E6   D0200PA00X-014441Y-015693X0320Y    R180 S3      
317SAS_B2_TX8P      J24   -2C7  D0150PA00X-013917Y-008362X0270Y    R180 S3      
317SAS_B2_TX8N      J23   -F6   D0200PA00X-014441Y-015142X0320Y    R180 S3      
317SAS_B2_TX8N      J24   -2C8  D0150PA00X-014213Y-007811X0270Y    R180 S3      
317SAS_B2_TX7P      J24   -2D7  D0150PA00X-013917Y-009858X0270Y    R180 S3      
317SAS_B2_TX7P      J23   -G5   D0200PA00X-013654Y-014551X0320Y    R180 S3      
317SAS_B2_TX7N      J24   -2D8  D0150PA00X-014213Y-009307X0270Y    R180 S3      
317SAS_B2_TX7N      J23   -H5   D0200PA00X-013654Y-014000X0320Y    R180 S3      
317SAS_B2_TX6P      J23   -A5   D0200PA00X-013654Y-017858X0320Y    R180 S3      
317SAS_B2_TX6P      J24   -2C4  D0150PA00X-013031Y-008362X0270Y    R180 S3      
317SAS_B2_TX6N      J23   -B5   D0200PA00X-013654Y-017307X0320Y    R180 S3      
317SAS_B2_TX6N      J24   -2C5  D0150PA00X-013327Y-007811X0270Y    R180 S3      
317SAS_B2_TX5P      J24   -2D4  D0150PA00X-013031Y-009858X0270Y    R180 S3      
317SAS_B2_TX5P      J23   -E4   D0200PA00X-012866Y-015693X0320Y    R180 S3      
317SAS_B2_TX5N      J24   -2D5  D0150PA00X-013327Y-009307X0270Y    R180 S3      
317SAS_B2_TX5N      J23   -F4   D0200PA00X-012866Y-015142X0320Y    R180 S3      
317SAS_B2_TX4P      J24   -1C7  D0150PA00X-009587Y-008362X0270Y    R180 S3      
317SAS_B2_TX4P      J23   -G3   D0200PA00X-012079Y-014551X0320Y    R180 S3      
317SAS_B2_TX4N      J24   -1C8  D0150PA00X-009882Y-007811X0270Y    R180 S3      
317SAS_B2_TX4N      J23   -H3   D0200PA00X-012079Y-014000X0320Y    R180 S3      
317SAS_B2_TX3P      J24   -1D7  D0150PA00X-009587Y-009858X0270Y    R180 S3      
317SAS_B2_TX3P      J23   -E2   D0200PA00X-011291Y-015693X0320Y    R180 S3      
317SAS_B2_TX3N      J24   -1D8  D0150PA00X-009882Y-009307X0270Y    R180 S3      
317SAS_B2_TX3N      J23   -F2   D0200PA00X-011291Y-015142X0320Y    R180 S3      
317SAS_B2_TX2P      J23   -G1   D0200PA00X-010504Y-014551X0320Y    R180 S3      
317SAS_B2_TX2P      J24   -1C4  D0150PA00X-008701Y-008362X0270Y    R180 S3      
317SAS_B2_TX2N      J24   -1C5  D0150PA00X-008996Y-007811X0270Y    R180 S3      
317SAS_B2_TX2N      J23   -H1   D0200PA00X-010504Y-014000X0320Y    R180 S3      
317SAS_B2_TX1P      J24   -1D4  D0150PA00X-008701Y-009858X0270Y    R180 S3      
317SAS_B2_TX1P      J23   -A1   D0200PA00X-010504Y-017858X0320Y    R180 S3      
317SAS_B2_TX1N      J23   -B1   D0200PA00X-010504Y-017307X0320Y    R180 S3      
317SAS_B2_TX1N      J24   -1D5  D0150PA00X-008996Y-009307X0270Y    R180 S3      
317SAS_B2_RX8P      J24   -2A7  D0150PA00X-013917Y-005370X0270Y    R180 S3      
317SAS_B2_RX8P      J23   -B6   D0200PA00X-014441Y-017346X0320Y    R180 S3      
317SAS_B2_RX8N      J24   -2A8  D0150PA00X-014213Y-004819X0270Y    R180 S3      
317SAS_B2_RX8N      J23   -C6   D0200PA00X-014441Y-016795X0320Y    R180 S3      
317SAS_B2_RX7P      J23   -H6   D0200PA00X-014441Y-014039X0320Y    R180 S3      
317SAS_B2_RX7P      J24   -2B7  D0150PA00X-013917Y-006866X0270Y    R180 S3      
317SAS_B2_RX7N      J23   -I6   D0200PA00X-014441Y-013488X0320Y    R180 S3      
317SAS_B2_RX7N      J24   -2B8  D0150PA00X-014213Y-006315X0270Y    R180 S3      
317SAS_B2_RX6P      J24   -2A4  D0150PA00X-013031Y-005370X0270Y    R180 S3      
317SAS_B2_RX6P      J23   -D5   D0200PA00X-013654Y-016205X0320Y    R180 S3      
317SAS_B2_RX6N      J24   -2A5  D0150PA00X-013327Y-004819X0270Y    R180 S3      
317SAS_B2_RX6N      J23   -E5   D0200PA00X-013654Y-015654X0320Y    R180 S3      
317SAS_B2_RX5P      J23   -H4   D0200PA00X-012866Y-014039X0320Y    R180 S3      
317SAS_B2_RX5P      J24   -2B4  D0150PA00X-013031Y-006866X0270Y    R180 S3      
317SAS_B2_RX5N      J23   -I4   D0200PA00X-012866Y-013488X0320Y    R180 S3      
317SAS_B2_RX5N      J24   -2B5  D0150PA00X-013327Y-006315X0270Y    R180 S3      
317SAS_B2_RX4P      J23   -D3   D0200PA00X-012079Y-016205X0320Y    R180 S3      
317SAS_B2_RX4P      J24   -1A7  D0150PA00X-009587Y-005370X0270Y    R180 S3      
317SAS_B2_RX4N      J23   -E3   D0200PA00X-012079Y-015654X0320Y    R180 S3      
317SAS_B2_RX4N      J24   -1A8  D0150PA00X-009882Y-004819X0270Y    R180 S3      
317SAS_B2_RX3P      J23   -B2   D0200PA00X-011291Y-017346X0320Y    R180 S3      
317SAS_B2_RX3P      J24   -1B7  D0150PA00X-009587Y-006866X0270Y    R180 S3      
317SAS_B2_RX3N      J23   -C2   D0200PA00X-011291Y-016795X0320Y    R180 S3      
317SAS_B2_RX3N      J24   -1B8  D0150PA00X-009882Y-006315X0270Y    R180 S3      
317SAS_B2_RX2P      J24   -1A4  D0150PA00X-008701Y-005370X0270Y    R180 S3      
317SAS_B2_RX2P      J23   -H2   D0200PA00X-011291Y-014039X0320Y    R180 S3      
317SAS_B2_RX2N      J24   -1A5  D0150PA00X-008996Y-004819X0270Y    R180 S3      
317SAS_B2_RX2N      J23   -I2   D0200PA00X-011291Y-013488X0320Y    R180 S3      
317SAS_B2_RX1P      J23   -D1   D0200PA00X-010504Y-016205X0320Y    R180 S3      
317SAS_B2_RX1P      J24   -1B4  D0150PA00X-008701Y-006866X0270Y    R180 S3      
317SAS_B2_RX1N      J23   -E1   D0200PA00X-010504Y-015654X0320Y    R180 S3      
317SAS_B2_RX1N      J24   -1B5  D0150PA00X-008996Y-006315X0270Y    R180 S3      
317SAS_B1_TX8P      J11   -E6   D0200PA00X-101449Y-015693X0320Y    R180 S3      
317SAS_B1_TX8P      J12   -2C7  D0150PA00X-100925Y-008362X0270Y    R180 S3      
317SAS_B1_TX8N      J11   -F6   D0200PA00X-101449Y-015142X0320Y    R180 S3      
317SAS_B1_TX8N      J12   -2C8  D0150PA00X-101220Y-007811X0270Y    R180 S3      
317SAS_B1_TX7P      J11   -G5   D0200PA00X-100661Y-014551X0320Y    R180 S3      
317SAS_B1_TX7P      J12   -2D7  D0150PA00X-100925Y-009858X0270Y    R180 S3      
317SAS_B1_TX7N      J12   -2D8  D0150PA00X-101220Y-009307X0270Y    R180 S3      
317SAS_B1_TX7N      J11   -H5   D0200PA00X-100661Y-014000X0320Y    R180 S3      
317SAS_B1_TX6P      J11   -A5   D0200PA00X-100661Y-017858X0320Y    R180 S3      
317SAS_B1_TX6P      J12   -2C4  D0150PA00X-100039Y-008362X0270Y    R180 S3      
317SAS_B1_TX6N      J11   -B5   D0200PA00X-100661Y-017307X0320Y    R180 S3      
317SAS_B1_TX6N      J12   -2C5  D0150PA00X-100335Y-007811X0270Y    R180 S3      
317SAS_B1_TX5P      J11   -E4   D0200PA00X-099874Y-015693X0320Y    R180 S3      
317SAS_B1_TX5P      J12   -2D4  D0150PA00X-100039Y-009858X0270Y    R180 S3      
317SAS_B1_TX5N      J12   -2D5  D0150PA00X-100335Y-009307X0270Y    R180 S3      
317SAS_B1_TX5N      J11   -F4   D0200PA00X-099874Y-015142X0320Y    R180 S3      
317SAS_B1_TX4P      J11   -G3   D0200PA00X-099087Y-014551X0320Y    R180 S3      
317SAS_B1_TX4P      J12   -1C7  D0150PA00X-096594Y-008362X0270Y    R180 S3      
317SAS_B1_TX4N      J12   -1C8  D0150PA00X-096890Y-007811X0270Y    R180 S3      
317SAS_B1_TX4N      J11   -H3   D0200PA00X-099087Y-014000X0320Y    R180 S3      
317SAS_B1_TX3P      J11   -E2   D0200PA00X-098299Y-015693X0320Y    R180 S3      
317SAS_B1_TX3P      J12   -1D7  D0150PA00X-096594Y-009858X0270Y    R180 S3      
317SAS_B1_TX3N      J12   -1D8  D0150PA00X-096890Y-009307X0270Y    R180 S3      
317SAS_B1_TX3N      J11   -F2   D0200PA00X-098299Y-015142X0320Y    R180 S3      
317SAS_B1_TX2P      J11   -G1   D0200PA00X-097512Y-014551X0320Y    R180 S3      
317SAS_B1_TX2P      J12   -1C4  D0150PA00X-095709Y-008362X0270Y    R180 S3      
317SAS_B1_TX2N      J12   -1C5  D0150PA00X-096004Y-007811X0270Y    R180 S3      
317SAS_B1_TX2N      J11   -H1   D0200PA00X-097512Y-014000X0320Y    R180 S3      
317SAS_B1_TX1P      J12   -1D4  D0150PA00X-095709Y-009858X0270Y    R180 S3      
317SAS_B1_TX1P      J11   -A1   D0200PA00X-097512Y-017858X0320Y    R180 S3      
317SAS_B1_TX1N      J11   -B1   D0200PA00X-097512Y-017307X0320Y    R180 S3      
317SAS_B1_TX1N      J12   -1D5  D0150PA00X-096004Y-009307X0270Y    R180 S3      
317SAS_B1_RX8P      J12   -2A7  D0150PA00X-100925Y-005370X0270Y    R180 S3      
317SAS_B1_RX8P      J11   -B6   D0200PA00X-101449Y-017346X0320Y    R180 S3      
317SAS_B1_RX8N      J11   -C6   D0200PA00X-101449Y-016795X0320Y    R180 S3      
317SAS_B1_RX8N      J12   -2A8  D0150PA00X-101220Y-004819X0270Y    R180 S3      
317SAS_B1_RX7P      J11   -H6   D0200PA00X-101449Y-014039X0320Y    R180 S3      
317SAS_B1_RX7P      J12   -2B7  D0150PA00X-100925Y-006866X0270Y    R180 S3      
317SAS_B1_RX7N      J11   -I6   D0200PA00X-101449Y-013488X0320Y    R180 S3      
317SAS_B1_RX7N      J12   -2B8  D0150PA00X-101220Y-006315X0270Y    R180 S3      
317SAS_B1_RX6P      J12   -2A4  D0150PA00X-100039Y-005370X0270Y    R180 S3      
317SAS_B1_RX6P      J11   -D5   D0200PA00X-100661Y-016205X0320Y    R180 S3      
317SAS_B1_RX6N      J12   -2A5  D0150PA00X-100335Y-004819X0270Y    R180 S3      
317SAS_B1_RX6N      J11   -E5   D0200PA00X-100661Y-015654X0320Y    R180 S3      
317SAS_B1_RX5P      J11   -H4   D0200PA00X-099874Y-014039X0320Y    R180 S3      
317SAS_B1_RX5P      J12   -2B4  D0150PA00X-100039Y-006866X0270Y    R180 S3      
317SAS_B1_RX5N      J11   -I4   D0200PA00X-099874Y-013488X0320Y    R180 S3      
317SAS_B1_RX5N      J12   -2B5  D0150PA00X-100335Y-006315X0270Y    R180 S3      
317SAS_B1_RX4P      J11   -D3   D0200PA00X-099087Y-016205X0320Y    R180 S3      
317SAS_B1_RX4P      J12   -1A7  D0150PA00X-096594Y-005370X0270Y    R180 S3      
317SAS_B1_RX4N      J12   -1A8  D0150PA00X-096890Y-004819X0270Y    R180 S3      
317SAS_B1_RX4N      J11   -E3   D0200PA00X-099087Y-015654X0320Y    R180 S3      
317SAS_B1_RX3P      J12   -1B7  D0150PA00X-096594Y-006866X0270Y    R180 S3      
317SAS_B1_RX3P      J11   -B2   D0200PA00X-098299Y-017346X0320Y    R180 S3      
317SAS_B1_RX3N      J11   -C2   D0200PA00X-098299Y-016795X0320Y    R180 S3      
317SAS_B1_RX3N      J12   -1B8  D0150PA00X-096890Y-006315X0270Y    R180 S3      
317SAS_B1_RX2P      J12   -1A4  D0150PA00X-095709Y-005370X0270Y    R180 S3      
317SAS_B1_RX2P      J11   -H2   D0200PA00X-098299Y-014039X0320Y    R180 S3      
317SAS_B1_RX2N      J12   -1A5  D0150PA00X-096004Y-004819X0270Y    R180 S3      
317SAS_B1_RX2N      J11   -I2   D0200PA00X-098299Y-013488X0320Y    R180 S3      
317SAS_B1_RX1P      J11   -D1   D0200PA00X-097512Y-016205X0320Y    R180 S3      
317SAS_B1_RX1P      J12   -1B4  D0150PA00X-095709Y-006866X0270Y    R180 S3      
317SAS_B1_RX1N      J11   -E1   D0200PA00X-097512Y-015654X0320Y    R180 S3      
317SAS_B1_RX1N      J12   -1B5  D0150PA00X-096004Y-006315X0270Y    R180 S3      
327PCIE_WAKE_B2_N   J14   -159        A01X-059411Y-007439X0250Y    R090 S1      
317PCIE_WAKE_B2_N   VIA   -    MD0100PA00X-059661Y-007189X0220Y         S0      
317PCIE_WAKE_B2_N   J13   -H4   D0200PA00X-069866Y-014000X0320Y    R180 S3      
327PCIE_WAKE_B1_N   J2    -159        A01X-146419Y-007439X0250Y    R090 S1      
317PCIE_WAKE_B1_N   VIA   -    MD0100PA00X-146669Y-007189X0220Y         S0      
317PCIE_WAKE_B1_N   J1    -H4   D0200PA00X-156874Y-014000X0320Y    R180 S3      
327m0016            J14   -100        A01X-060911Y-010939X0250Y    R090 S1      
317m0016            VIA   -    MD0100PA00X-061161Y-010689X0220Y         S0      
317m0016            J13   -D7   D0200PA00X-072228Y-016165X0320Y    R180 S3      
327m0017            J14   -115        A01X-061411Y-009939X0250Y    R090 S1      
317m0017            VIA   -    MD0100PA00X-061661Y-009689X0220Y         S0      
317m0017            J13   -E8   D0200PA00X-073016Y-015654X0320Y    R180 S3      
327m0018            J14   -2          A01X-061911Y-016939X0250Y    R090 S1      
317m0018            J13   -A1   D0200PA00X-067504Y-017819X0320Y0320R180 S3      
317m0019            J13   -B2   D0200PA00X-068291Y-017307X0320Y    R180 S3      
327m0019            J14   -17         A01X-062411Y-015939X0250Y    R090 S1      
327m0020            J14   -34         A01X-061911Y-014939X0250Y    R090 S1      
317m0020            J13   -A3   D0200PA00X-069079Y-017819X0320Y    R180 S3      
327m0021            J14   -49         A01X-062411Y-013939X0250Y    R090 S1      
317m0021            J13   -B4   D0200PA00X-069866Y-017307X0320Y    R180 S3      
317m0022            J13   -A5   D0200PA00X-070654Y-017819X0320Y    R180 S3      
327m0022            J14   -66         A01X-061911Y-012939X0250Y    R090 S1      
317m0023            J13   -B6   D0200PA00X-071441Y-017307X0320Y    R180 S3      
327m0023            J14   -81         A01X-062411Y-011939X0250Y    R090 S1      
327m0024            J14   -98         A01X-061911Y-010939X0250Y    R090 S1      
317m0024            J13   -A7   D0200PA00X-072228Y-017819X0320Y    R180 S3      
327m0025            J14   -4          A01X-060911Y-016939X0250Y    R090 S1      
317m0025            VIA   -    MD0100PA00X-061161Y-016689X0220Y         S0      
317m0025            J13   -D1   D0200PA00X-067504Y-016165X0320Y    R180 S3      
327m0026            J14   -19         A01X-061411Y-015939X0250Y    R090 S1      
317m0026            VIA   -    MD0100PA00X-061661Y-015689X0220Y         S0      
317m0026            J13   -E2   D0200PA00X-068291Y-015654X0320Y    R180 S3      
327m0027            J14   -36         A01X-060911Y-014939X0250Y    R090 S1      
317m0027            VIA   -    MD0100PA00X-061161Y-014689X0220Y         S0      
317m0027            J13   -D3   D0200PA00X-069079Y-016165X0320Y    R180 S3      
327m0028            J14   -51         A01X-061411Y-013939X0250Y    R090 S1      
317m0028            VIA   -    MD0100PA00X-061661Y-013689X0220Y         S0      
317m0028            J13   -E4   D0200PA00X-069866Y-015654X0320Y    R180 S3      
327m0029            J14   -68         A01X-060911Y-012939X0250Y    R090 S1      
317m0029            VIA   -    MD0100PA00X-061161Y-012689X0220Y         S0      
317m0029            J13   -D5   D0200PA00X-070654Y-016165X0320Y    R180 S3      
327m0030            J14   -83         A01X-061411Y-011939X0250Y    R090 S1      
317m0030            VIA   -    MD0100PA00X-061661Y-011689X0220Y         S0      
317m0030            J13   -E6   D0200PA00X-071441Y-015654X0320Y    R180 S3      
327m0031            J14   -113        A01X-062411Y-009939X0250Y    R090 S1      
317m0031            J13   -B8   D0200PA00X-073016Y-017307X0320Y    R180 S3      
327m0032            J14   -108        A01X-060911Y-010439X0250Y    R090 S1      
317m0032            VIA   -    MD0100PA00X-061161Y-010189X0220Y         S0      
317m0032            J13   -E7   D0200PA00X-072228Y-015614X0320Y    R180 S3      
327m0033            J14   -123        A01X-061411Y-009439X0250Y    R090 S1      
317m0033            VIA   -    MD0100PA00X-061661Y-009189X0220Y         S0      
317m0033            J13   -F8   D0200PA00X-073016Y-015102X0320Y    R180 S3      
327m0034            J14   -10         A01X-061911Y-016439X0250Y    R090 S1      
317m0034            J13   -B1   D0200PA00X-067504Y-017268X0320Y    R180 S3      
327m0035            J14   -25         A01X-062411Y-015439X0250Y    R090 S1      
317m0035            J13   -C2   D0200PA00X-068291Y-016756X0320Y    R180 S3      
317m0036            J13   -B3   D0200PA00X-069079Y-017268X0320Y    R180 S3      
327m0036            J14   -42         A01X-061911Y-014439X0250Y    R090 S1      
317m0037            J13   -C4   D0200PA00X-069866Y-016756X0320Y    R180 S3      
327m0037            J14   -57         A01X-062411Y-013439X0250Y    R090 S1      
317m0038            J13   -B5   D0200PA00X-070654Y-017268X0320Y    R180 S3      
327m0038            J14   -74         A01X-061911Y-012439X0250Y    R090 S1      
327m0039            J14   -89         A01X-062411Y-011439X0250Y    R090 S1      
317m0039            J13   -C6   D0200PA00X-071441Y-016756X0320Y    R180 S3      
327m0040            J14   -106        A01X-061911Y-010439X0250Y    R090 S1      
317m0040            J13   -B7   D0200PA00X-072228Y-017268X0320Y    R180 S3      
327m0041            J14   -12         A01X-060911Y-016439X0250Y    R090 S1      
317m0041            VIA   -    MD0100PA00X-061161Y-016189X0220Y         S0      
317m0041            J13   -E1   D0200PA00X-067504Y-015614X0320Y    R180 S3      
327m0042            J14   -27         A01X-061411Y-015439X0250Y    R090 S1      
317m0042            VIA   -    MD0100PA00X-061661Y-015189X0220Y         S0      
317m0042            J13   -F2   D0200PA00X-068291Y-015102X0320Y    R180 S3      
327m0043            J14   -44         A01X-060911Y-014439X0250Y    R090 S1      
317m0043            VIA   -    MD0100PA00X-061161Y-014189X0220Y         S0      
317m0043            J13   -E3   D0200PA00X-069079Y-015614X0320Y    R180 S3      
327m0044            J14   -59         A01X-061411Y-013439X0250Y    R090 S1      
317m0044            VIA   -    MD0100PA00X-061661Y-013189X0220Y         S0      
317m0044            J13   -F4   D0200PA00X-069866Y-015102X0320Y    R180 S3      
327m0045            J14   -76         A01X-060911Y-012439X0250Y    R090 S1      
317m0045            VIA   -    MD0100PA00X-061161Y-012189X0220Y         S0      
317m0045            J13   -E5   D0200PA00X-070654Y-015614X0320Y    R180 S3      
327m0046            J14   -91         A01X-061411Y-011439X0250Y    R090 S1      
317m0046            VIA   -    MD0100PA00X-061661Y-011189X0220Y         S0      
317m0046            J13   -F6   D0200PA00X-071441Y-015102X0320Y    R180 S3      
327m0047            J14   -121        A01X-062411Y-009439X0250Y    R090 S1      
317m0047            J13   -C8   D0200PA00X-073016Y-016756X0320Y    R180 S3      
317m0048            J1    -D7   D0200PA00X-159236Y-016165X0320Y    R180 S3      
317m0048            VIA   -    MD0100PA00X-148169Y-010689X0220Y         S0      
327m0048            J2    -100        A01X-147919Y-010939X0250Y    R090 S1      
317m0049            VIA   -    MD0100PA00X-148669Y-009689X0220Y         S0      
327m0049            J2    -115        A01X-148419Y-009939X0250Y    R090 S1      
317m0049            J1    -E8   D0200PA00X-160024Y-015654X0320Y    R180 S3      
327m0050            J2    -2          A01X-148919Y-016939X0250Y    R090 S1      
317m0050            J1    -A1   D0200PA00X-154512Y-017819X0320Y0320R180 S3      
317m0051            J1    -B2   D0200PA00X-155299Y-017307X0320Y    R180 S3      
327m0051            J2    -17         A01X-149419Y-015939X0250Y    R090 S1      
327m0052            J2    -34         A01X-148919Y-014939X0250Y    R090 S1      
317m0052            J1    -A3   D0200PA00X-156087Y-017819X0320Y    R180 S3      
327m0053            J2    -49         A01X-149419Y-013939X0250Y    R090 S1      
317m0053            J1    -B4   D0200PA00X-156874Y-017307X0320Y    R180 S3      
317m0054            J1    -A5   D0200PA00X-157661Y-017819X0320Y    R180 S3      
327m0054            J2    -66         A01X-148919Y-012939X0250Y    R090 S1      
317m0055            J1    -B6   D0200PA00X-158449Y-017307X0320Y    R180 S3      
327m0055            J2    -81         A01X-149419Y-011939X0250Y    R090 S1      
317m0056            J1    -A7   D0200PA00X-159236Y-017819X0320Y    R180 S3      
327m0056            J2    -98         A01X-148919Y-010939X0250Y    R090 S1      
317m0057            J1    -D1   D0200PA00X-154512Y-016165X0320Y    R180 S3      
317m0057            VIA   -    MD0100PA00X-148169Y-016689X0220Y         S0      
327m0057            J2    -4          A01X-147919Y-016939X0250Y    R090 S1      
317m0058            VIA   -    MD0100PA00X-148669Y-015689X0220Y         S0      
327m0058            J2    -19         A01X-148419Y-015939X0250Y    R090 S1      
317m0058            J1    -E2   D0200PA00X-155299Y-015654X0320Y    R180 S3      
317m0059            VIA   -    MD0100PA00X-148169Y-014689X0220Y         S0      
327m0059            J2    -36         A01X-147919Y-014939X0250Y    R090 S1      
317m0059            J1    -D3   D0200PA00X-156087Y-016165X0320Y    R180 S3      
317m0060            VIA   -    MD0100PA00X-148669Y-013689X0220Y         S0      
327m0060            J2    -51         A01X-148419Y-013939X0250Y    R090 S1      
317m0060            J1    -E4   D0200PA00X-156874Y-015654X0320Y    R180 S3      
317m0061            VIA   -    MD0100PA00X-148169Y-012689X0220Y         S0      
327m0061            J2    -68         A01X-147919Y-012939X0250Y    R090 S1      
317m0061            J1    -D5   D0200PA00X-157661Y-016165X0320Y    R180 S3      
317m0062            J1    -E6   D0200PA00X-158449Y-015654X0320Y    R180 S3      
317m0062            VIA   -    MD0100PA00X-148669Y-011689X0220Y         S0      
327m0062            J2    -83         A01X-148419Y-011939X0250Y    R090 S1      
327m0063            J2    -113        A01X-149419Y-009939X0250Y    R090 S1      
317m0063            J1    -B8   D0200PA00X-160024Y-017307X0320Y    R180 S3      
317m0064            J1    -E7   D0200PA00X-159236Y-015614X0320Y    R180 S3      
317m0064            VIA   -    MD0100PA00X-148169Y-010189X0220Y         S0      
327m0064            J2    -108        A01X-147919Y-010439X0250Y    R090 S1      
317m0065            J1    -F8   D0200PA00X-160024Y-015102X0320Y    R180 S3      
317m0065            VIA   -    MD0100PA00X-148669Y-009189X0220Y         S0      
327m0065            J2    -123        A01X-148419Y-009439X0250Y    R090 S1      
327m0066            J2    -10         A01X-148919Y-016439X0250Y    R090 S1      
317m0066            J1    -B1   D0200PA00X-154512Y-017268X0320Y    R180 S3      
327m0067            J2    -25         A01X-149419Y-015439X0250Y    R090 S1      
317m0067            J1    -C2   D0200PA00X-155299Y-016756X0320Y    R180 S3      
317m0068            J1    -B3   D0200PA00X-156087Y-017268X0320Y    R180 S3      
327m0068            J2    -42         A01X-148919Y-014439X0250Y    R090 S1      
317m0069            J1    -C4   D0200PA00X-156874Y-016756X0320Y    R180 S3      
327m0069            J2    -57         A01X-149419Y-013439X0250Y    R090 S1      
317m0070            J1    -B5   D0200PA00X-157661Y-017268X0320Y    R180 S3      
327m0070            J2    -74         A01X-148919Y-012439X0250Y    R090 S1      
327m0071            J2    -89         A01X-149419Y-011439X0250Y    R090 S1      
317m0071            J1    -C6   D0200PA00X-158449Y-016756X0320Y    R180 S3      
327m0072            J2    -106        A01X-148919Y-010439X0250Y    R090 S1      
317m0072            J1    -B7   D0200PA00X-159236Y-017268X0320Y    R180 S3      
317m0073            J1    -E1   D0200PA00X-154512Y-015614X0320Y    R180 S3      
317m0073            VIA   -    MD0100PA00X-148169Y-016189X0220Y         S0      
327m0073            J2    -12         A01X-147919Y-016439X0250Y    R090 S1      
317m0074            VIA   -    MD0100PA00X-148669Y-015189X0220Y         S0      
327m0074            J2    -27         A01X-148419Y-015439X0250Y    R090 S1      
317m0074            J1    -F2   D0200PA00X-155299Y-015102X0320Y    R180 S3      
317m0075            VIA   -    MD0100PA00X-148169Y-014189X0220Y         S0      
327m0075            J2    -44         A01X-147919Y-014439X0250Y    R090 S1      
317m0075            J1    -E3   D0200PA00X-156087Y-015614X0320Y    R180 S3      
317m0076            VIA   -    MD0100PA00X-148669Y-013189X0220Y         S0      
327m0076            J2    -59         A01X-148419Y-013439X0250Y    R090 S1      
317m0076            J1    -F4   D0200PA00X-156874Y-015102X0320Y    R180 S3      
317m0077            VIA   -    MD0100PA00X-148169Y-012189X0220Y         S0      
327m0077            J2    -76         A01X-147919Y-012439X0250Y    R090 S1      
317m0077            J1    -E5   D0200PA00X-157661Y-015614X0320Y    R180 S3      
317m0078            J1    -F6   D0200PA00X-158449Y-015102X0320Y    R180 S3      
317m0078            VIA   -    MD0100PA00X-148669Y-011189X0220Y         S0      
327m0078            J2    -91         A01X-148419Y-011439X0250Y    R090 S1      
327m0079            J2    -121        A01X-149419Y-009439X0250Y    R090 S1      
317m0079            J1    -C8   D0200PA00X-160024Y-016756X0320Y    R180 S3      
327m0080            J14   -152        A01X-058911Y-007939X0250Y    R090 S1      
317m0080            VIA   -    MD0100PA00X-059161Y-007689X0220Y         S0      
317m0080            J13   -G1   D0200PA00X-067504Y-014512X0320Y    R180 S3      
317m0081            VIA   -    MD0100PA00X-059661Y-008189X0220Y         S0      
327m0081            J14   -143        A01X-059411Y-008439X0250Y    R090 S1      
317m0081            J13   -H1   D0200PA00X-067504Y-013961X0320Y    R180 S3      
327m0082            J14   -151        A01X-059411Y-007939X0250Y    R090 S1      
317m0082            VIA   -    MD0100PA00X-059661Y-007689X0220Y         S0      
317m0082            J13   -H2   D0200PA00X-068291Y-014000X0320Y    R180 S3      
327m0083            J14   -150        A01X-059911Y-007939X0250Y    R090 S1      
317m0083            VIA   -    MD0100PA00X-060161Y-007689X0220Y         S0      
317m0083            J13   -I2   D0200PA00X-068291Y-013449X0320Y    R180 S3      
327m0084            J2    -152        A01X-145919Y-007939X0250Y    R090 S1      
317m0084            VIA   -    MD0100PA00X-146169Y-007689X0220Y         S0      
317m0084            J1    -G1   D0200PA00X-154512Y-014512X0320Y    R180 S3      
327m0085            J2    -143        A01X-146419Y-008439X0250Y    R090 S1      
317m0085            VIA   -    MD0100PA00X-146669Y-008189X0220Y         S0      
317m0085            J1    -H1   D0200PA00X-154512Y-013961X0320Y    R180 S3      
327m0086            J2    -151        A01X-146419Y-007939X0250Y    R090 S1      
317m0086            VIA   -    MD0100PA00X-146669Y-007689X0220Y         S0      
317m0086            J1    -H2   D0200PA00X-155299Y-014000X0320Y    R180 S3      
327m0087            J2    -150        A01X-146919Y-007939X0250Y    R090 S1      
317m0087            VIA   -    MD0100PA00X-147169Y-007689X0220Y         S0      
317m0087            J1    -I2   D0200PA00X-155299Y-013449X0320Y    R180 S3      
327m0088            J14   -148        A01X-060911Y-007939X0250Y    R090 S1      
317m0088            VIA   -    MD0100PA00X-061161Y-007689X0220Y         S0      
317m0088            J13   -H3   D0200PA00X-069079Y-013961X0320Y    R180 S3      
327m0089            J14   -149        A01X-060411Y-007939X0250Y    R090 S1      
317m0089            VIA   -    MD0100PA00X-060661Y-007689X0220Y         S0      
317m0089            J13   -G3   D0200PA00X-069079Y-014512X0320Y    R180 S3      
327m0090            J2    -148        A01X-147919Y-007939X0250Y    R090 S1      
317m0090            VIA   -    MD0100PA00X-148169Y-007689X0220Y         S0      
317m0090            J1    -H3   D0200PA00X-156087Y-013961X0320Y    R180 S3      
327m0091            J2    -149        A01X-147419Y-007939X0250Y    R090 S1      
317m0091            VIA   -    MD0100PA00X-147669Y-007689X0220Y         S0      
317m0091            J1    -G3   D0200PA00X-156087Y-014512X0320Y    R180 S3      
327m0092            J14   -104        A01X-058911Y-010939X0250Y    R090 S1      
317m0092            VIA   -    MD0100PA00X-059161Y-010689X0220Y         S0      
317m0092            J13   -M7   D0200PA00X-072228Y-011205X0320Y    R180 S3      
327m0093            J14   -119        A01X-059411Y-009939X0250Y    R090 S1      
317m0093            VIA   -    MD0100PA00X-059661Y-009689X0220Y         S0      
317m0093            J13   -N8   D0200PA00X-073016Y-010693X0320Y    R180 S3      
327m0094            J14   -6          A01X-059911Y-016939X0250Y    R090 S1      
317m0094            VIA   -    MD0100PA00X-060161Y-016689X0220Y         S0      
317m0094            J13   -J1   D0200PA00X-067504Y-012858X0320Y    R180 S3      
327m0095            J14   -21         A01X-060411Y-015939X0250Y    R090 S1      
317m0095            VIA   -    MD0100PA00X-060661Y-015689X0220Y         S0      
317m0095            J13   -K2   D0200PA00X-068291Y-012346X0320Y    R180 S3      
327m0096            J14   -38         A01X-059911Y-014939X0250Y    R090 S1      
317m0096            VIA   -    MD0100PA00X-060161Y-014689X0220Y         S0      
317m0096            J13   -J3   D0200PA00X-069079Y-012858X0320Y    R180 S3      
327m0097            J14   -53         A01X-060411Y-013939X0250Y    R090 S1      
317m0097            VIA   -    MD0100PA00X-060661Y-013689X0220Y         S0      
317m0097            J13   -K4   D0200PA00X-069866Y-012346X0320Y    R180 S3      
327m0098            J14   -70         A01X-059911Y-012939X0250Y    R090 S1      
317m0098            VIA   -    MD0100PA00X-060161Y-012689X0220Y         S0      
317m0098            J13   -J5   D0200PA00X-070654Y-012858X0320Y    R180 S3      
327m0099            J14   -85         A01X-060411Y-011939X0250Y    R090 S1      
317m0099            VIA   -    MD0100PA00X-060661Y-011689X0220Y         S0      
317m0099            J13   -K6   D0200PA00X-071441Y-012346X0320Y    R180 S3      
327m0100            J14   -102        A01X-059911Y-010939X0250Y    R090 S1      
317m0100            VIA   -    MD0100PA00X-060161Y-010689X0220Y         S0      
317m0100            J13   -J7   D0200PA00X-072228Y-012858X0320Y    R180 S3      
327m0101            J14   -8          A01X-058911Y-016939X0250Y    R090 S1      
317m0101            VIA   -    MD0100PA00X-059161Y-016689X0220Y         S0      
317m0101            J13   -M1   D0200PA00X-067504Y-011205X0320Y    R180 S3      
327m0102            J14   -23         A01X-059411Y-015939X0250Y    R090 S1      
317m0102            VIA   -    MD0100PA00X-059661Y-015689X0220Y         S0      
317m0102            J13   -N2   D0200PA00X-068291Y-010693X0320Y    R180 S3      
327m0103            J14   -40         A01X-058911Y-014939X0250Y    R090 S1      
317m0103            VIA   -    MD0100PA00X-059161Y-014689X0220Y         S0      
317m0103            J13   -M3   D0200PA00X-069079Y-011205X0320Y    R180 S3      
327m0104            J14   -55         A01X-059411Y-013939X0250Y    R090 S1      
317m0104            VIA   -    MD0100PA00X-059661Y-013689X0220Y         S0      
317m0104            J13   -N4   D0200PA00X-069866Y-010693X0320Y    R180 S3      
327m0105            J14   -72         A01X-058911Y-012939X0250Y    R090 S1      
317m0105            VIA   -    MD0100PA00X-059161Y-012689X0220Y         S0      
317m0105            J13   -M5   D0200PA00X-070654Y-011205X0320Y    R180 S3      
327m0106            J14   -87         A01X-059411Y-011939X0250Y    R090 S1      
317m0106            VIA   -    MD0100PA00X-059661Y-011689X0220Y         S0      
317m0106            J13   -N6   D0200PA00X-071441Y-010693X0320Y    R180 S3      
327m0107            J14   -117        A01X-060411Y-009939X0250Y    R090 S1      
317m0107            VIA   -    MD0100PA00X-060661Y-009689X0220Y         S0      
317m0107            J13   -K8   D0200PA00X-073016Y-012346X0320Y    R180 S3      
327m0108            J14   -112        A01X-058911Y-010439X0250Y    R090 S1      
317m0108            VIA   -    MD0100PA00X-059161Y-010189X0220Y         S0      
317m0108            J13   -N7   D0200PA00X-072228Y-010654X0320Y    R180 S3      
327m0109            J14   -127        A01X-059411Y-009439X0250Y    R090 S1      
317m0109            VIA   -    MD0100PA00X-059661Y-009189X0220Y         S0      
317m0109            J13   -O8   D0200PA00X-073016Y-010142X0320Y    R180 S3      
327m0110            J14   -14         A01X-059911Y-016439X0250Y    R090 S1      
317m0110            VIA   -    MD0100PA00X-060161Y-016189X0220Y         S0      
317m0110            J13   -K1   D0200PA00X-067504Y-012307X0320Y    R180 S3      
327m0111            J14   -29         A01X-060411Y-015439X0250Y    R090 S1      
317m0111            VIA   -    MD0100PA00X-060661Y-015189X0220Y         S0      
317m0111            J13   -L2   D0200PA00X-068291Y-011795X0320Y    R180 S3      
327m0112            J14   -46         A01X-059911Y-014439X0250Y    R090 S1      
317m0112            VIA   -    MD0100PA00X-060161Y-014189X0220Y         S0      
317m0112            J13   -K3   D0200PA00X-069079Y-012307X0320Y    R180 S3      
327m0113            J14   -61         A01X-060411Y-013439X0250Y    R090 S1      
317m0113            VIA   -    MD0100PA00X-060661Y-013189X0220Y         S0      
317m0113            J13   -L4   D0200PA00X-069866Y-011795X0320Y    R180 S3      
327m0114            J14   -78         A01X-059911Y-012439X0250Y    R090 S1      
317m0114            VIA   -    MD0100PA00X-060161Y-012189X0220Y         S0      
317m0114            J13   -K5   D0200PA00X-070654Y-012307X0320Y    R180 S3      
327m0115            J14   -93         A01X-060411Y-011439X0250Y    R090 S1      
317m0115            VIA   -    MD0100PA00X-060661Y-011189X0220Y         S0      
317m0115            J13   -L6   D0200PA00X-071441Y-011795X0320Y    R180 S3      
327m0116            J14   -110        A01X-059911Y-010439X0250Y    R090 S1      
317m0116            VIA   -    MD0100PA00X-060161Y-010189X0220Y         S0      
317m0116            J13   -K7   D0200PA00X-072228Y-012307X0320Y    R180 S3      
317m0117            J13   -N1   D0200PA00X-067504Y-010654X0320Y    R180 S3      
327m0117            J14   -16         A01X-058911Y-016439X0250Y    R090 S1      
317m0117            VIA   -    MD0100PA00X-059161Y-016189X0220Y         S0      
327m0118            J14   -31         A01X-059411Y-015439X0250Y    R090 S1      
317m0118            VIA   -    MD0100PA00X-059661Y-015189X0220Y         S0      
317m0118            J13   -O2   D0200PA00X-068291Y-010142X0320Y    R180 S3      
327m0119            J14   -48         A01X-058911Y-014439X0250Y    R090 S1      
317m0119            VIA   -    MD0100PA00X-059161Y-014189X0220Y         S0      
317m0119            J13   -N3   D0200PA00X-069079Y-010654X0320Y    R180 S3      
327m0120            J14   -63         A01X-059411Y-013439X0250Y    R090 S1      
317m0120            VIA   -    MD0100PA00X-059661Y-013189X0220Y         S0      
317m0120            J13   -O4   D0200PA00X-069866Y-010142X0320Y    R180 S3      
327m0121            J14   -80         A01X-058911Y-012439X0250Y    R090 S1      
317m0121            VIA   -    MD0100PA00X-059161Y-012189X0220Y         S0      
317m0121            J13   -N5   D0200PA00X-070654Y-010654X0320Y    R180 S3      
327m0122            J14   -95         A01X-059411Y-011439X0250Y    R090 S1      
317m0122            VIA   -    MD0100PA00X-059661Y-011189X0220Y         S0      
317m0122            J13   -O6   D0200PA00X-071441Y-010142X0320Y    R180 S3      
327m0123            J14   -125        A01X-060411Y-009439X0250Y    R090 S1      
317m0123            VIA   -    MD0100PA00X-060661Y-009189X0220Y         S0      
317m0123            J13   -L8   D0200PA00X-073016Y-011795X0320Y    R180 S3      
317m0124            VIA   -    MD0100PA00X-146169Y-010689X0220Y         S0      
327m0124            J2    -104        A01X-145919Y-010939X0250Y    R090 S1      
317m0124            J1    -M7   D0200PA00X-159236Y-011205X0320Y    R180 S3      
317m0125            VIA   -    MD0100PA00X-146669Y-009689X0220Y         S0      
327m0125            J2    -119        A01X-146419Y-009939X0250Y    R090 S1      
317m0125            J1    -N8   D0200PA00X-160024Y-010693X0320Y    R180 S3      
317m0126            J1    -J1   D0200PA00X-154512Y-012858X0320Y    R180 S3      
317m0126            VIA   -    MD0100PA00X-147169Y-016689X0220Y         S0      
327m0126            J2    -6          A01X-146919Y-016939X0250Y    R090 S1      
317m0127            J1    -K2   D0200PA00X-155299Y-012346X0320Y    R180 S3      
317m0127            VIA   -    MD0100PA00X-147669Y-015689X0220Y         S0      
327m0127            J2    -21         A01X-147419Y-015939X0250Y    R090 S1      
317m0128            VIA   -    MD0100PA00X-147169Y-014689X0220Y         S0      
327m0128            J2    -38         A01X-146919Y-014939X0250Y    R090 S1      
317m0128            J1    -J3   D0200PA00X-156087Y-012858X0320Y    R180 S3      
317m0129            VIA   -    MD0100PA00X-147669Y-013689X0220Y         S0      
327m0129            J2    -53         A01X-147419Y-013939X0250Y    R090 S1      
317m0129            J1    -K4   D0200PA00X-156874Y-012346X0320Y    R180 S3      
317m0130            VIA   -    MD0100PA00X-147169Y-012689X0220Y         S0      
327m0130            J2    -70         A01X-146919Y-012939X0250Y    R090 S1      
317m0130            J1    -J5   D0200PA00X-157661Y-012858X0320Y    R180 S3      
317m0131            VIA   -    MD0100PA00X-147669Y-011689X0220Y         S0      
327m0131            J2    -85         A01X-147419Y-011939X0250Y    R090 S1      
317m0131            J1    -K6   D0200PA00X-158449Y-012346X0320Y    R180 S3      
317m0132            VIA   -    MD0100PA00X-147169Y-010689X0220Y         S0      
327m0132            J2    -102        A01X-146919Y-010939X0250Y    R090 S1      
317m0132            J1    -J7   D0200PA00X-159236Y-012858X0320Y    R180 S3      
317m0133            VIA   -    MD0100PA00X-146169Y-016689X0220Y         S0      
327m0133            J2    -8          A01X-145919Y-016939X0250Y    R090 S1      
317m0133            J1    -M1   D0200PA00X-154512Y-011205X0320Y    R180 S3      
317m0134            VIA   -    MD0100PA00X-146669Y-015689X0220Y         S0      
327m0134            J2    -23         A01X-146419Y-015939X0250Y    R090 S1      
317m0134            J1    -N2   D0200PA00X-155299Y-010693X0320Y    R180 S3      
317m0135            VIA   -    MD0100PA00X-146169Y-014689X0220Y         S0      
327m0135            J2    -40         A01X-145919Y-014939X0250Y    R090 S1      
317m0135            J1    -M3   D0200PA00X-156087Y-011205X0320Y    R180 S3      
317m0136            VIA   -    MD0100PA00X-146669Y-013689X0220Y         S0      
327m0136            J2    -55         A01X-146419Y-013939X0250Y    R090 S1      
317m0136            J1    -N4   D0200PA00X-156874Y-010693X0320Y    R180 S3      
317m0137            VIA   -    MD0100PA00X-146169Y-012689X0220Y         S0      
327m0137            J2    -72         A01X-145919Y-012939X0250Y    R090 S1      
317m0137            J1    -M5   D0200PA00X-157661Y-011205X0320Y    R180 S3      
317m0138            VIA   -    MD0100PA00X-146669Y-011689X0220Y         S0      
327m0138            J2    -87         A01X-146419Y-011939X0250Y    R090 S1      
317m0138            J1    -N6   D0200PA00X-158449Y-010693X0320Y    R180 S3      
317m0139            VIA   -    MD0100PA00X-147669Y-009689X0220Y         S0      
327m0139            J2    -117        A01X-147419Y-009939X0250Y    R090 S1      
317m0139            J1    -K8   D0200PA00X-160024Y-012346X0320Y    R180 S3      
317m0140            VIA   -    MD0100PA00X-146169Y-010189X0220Y         S0      
327m0140            J2    -112        A01X-145919Y-010439X0250Y    R090 S1      
317m0140            J1    -N7   D0200PA00X-159236Y-010654X0320Y    R180 S3      
317m0141            VIA   -    MD0100PA00X-146669Y-009189X0220Y         S0      
327m0141            J2    -127        A01X-146419Y-009439X0250Y    R090 S1      
317m0141            J1    -O8   D0200PA00X-160024Y-010142X0320Y    R180 S3      
317m0142            J1    -K1   D0200PA00X-154512Y-012307X0320Y    R180 S3      
317m0142            VIA   -    MD0100PA00X-147169Y-016189X0220Y         S0      
327m0142            J2    -14         A01X-146919Y-016439X0250Y    R090 S1      
317m0143            J1    -L2   D0200PA00X-155299Y-011795X0320Y    R180 S3      
317m0143            VIA   -    MD0100PA00X-147669Y-015189X0220Y         S0      
327m0143            J2    -29         A01X-147419Y-015439X0250Y    R090 S1      
317m0144            VIA   -    MD0100PA00X-147169Y-014189X0220Y         S0      
327m0144            J2    -46         A01X-146919Y-014439X0250Y    R090 S1      
317m0144            J1    -K3   D0200PA00X-156087Y-012307X0320Y    R180 S3      
317m0145            VIA   -    MD0100PA00X-147669Y-013189X0220Y         S0      
327m0145            J2    -61         A01X-147419Y-013439X0250Y    R090 S1      
317m0145            J1    -L4   D0200PA00X-156874Y-011795X0320Y    R180 S3      
317m0146            VIA   -    MD0100PA00X-147169Y-012189X0220Y         S0      
327m0146            J2    -78         A01X-146919Y-012439X0250Y    R090 S1      
317m0146            J1    -K5   D0200PA00X-157661Y-012307X0320Y    R180 S3      
317m0147            VIA   -    MD0100PA00X-147669Y-011189X0220Y         S0      
327m0147            J2    -93         A01X-147419Y-011439X0250Y    R090 S1      
317m0147            J1    -L6   D0200PA00X-158449Y-011795X0320Y    R180 S3      
317m0148            VIA   -    MD0100PA00X-147169Y-010189X0220Y         S0      
327m0148            J2    -110        A01X-146919Y-010439X0250Y    R090 S1      
317m0148            J1    -K7   D0200PA00X-159236Y-012307X0320Y    R180 S3      
317m0149            VIA   -    MD0100PA00X-146169Y-016189X0220Y         S0      
327m0149            J2    -16         A01X-145919Y-016439X0250Y    R090 S1      
317m0149            J1    -N1   D0200PA00X-154512Y-010654X0320Y    R180 S3      
317m0150            VIA   -    MD0100PA00X-146669Y-015189X0220Y         S0      
327m0150            J2    -31         A01X-146419Y-015439X0250Y    R090 S1      
317m0150            J1    -O2   D0200PA00X-155299Y-010142X0320Y    R180 S3      
317m0151            VIA   -    MD0100PA00X-146169Y-014189X0220Y         S0      
327m0151            J2    -48         A01X-145919Y-014439X0250Y    R090 S1      
317m0151            J1    -N3   D0200PA00X-156087Y-010654X0320Y    R180 S3      
317m0152            VIA   -    MD0100PA00X-146669Y-013189X0220Y         S0      
327m0152            J2    -63         A01X-146419Y-013439X0250Y    R090 S1      
317m0152            J1    -O4   D0200PA00X-156874Y-010142X0320Y    R180 S3      
317m0153            VIA   -    MD0100PA00X-146169Y-012189X0220Y         S0      
327m0153            J2    -80         A01X-145919Y-012439X0250Y    R090 S1      
317m0153            J1    -N5   D0200PA00X-157661Y-010654X0320Y    R180 S3      
317m0154            VIA   -    MD0100PA00X-146669Y-011189X0220Y         S0      
327m0154            J2    -95         A01X-146419Y-011439X0250Y    R090 S1      
317m0154            J1    -O6   D0200PA00X-158449Y-010142X0320Y    R180 S3      
317m0155            VIA   -    MD0100PA00X-147669Y-009189X0220Y         S0      
327m0155            J2    -125        A01X-147419Y-009439X0250Y    R090 S1      
317m0155            J1    -L8   D0200PA00X-160024Y-011795X0320Y    R180 S3      
327P3V3_B2_QSFP     FS3   -1          A01X-026151Y-018000X0200Y0230R090 S1      
327P3V3_B2_QSFP     FS4   -2          A01X-021839Y-017990X0200Y0230R090 S1      
317P3V3_B2_QSFP     VIA   -    MD0100PA00X-021450Y-017980X0220Y    R180 S0      
317P3V3_B2_QSFP     VIA   -    MD0100PA00X-026520Y-017985X0220Y    R180 S0      
317P3V3_B2_QSFP     VIA   -    MD0100PA00X-024325Y-018221X0220Y         S0      
327P3V3_B2_QSFP     R41   -1          A01X-024325Y-017921X0280Y0320R090 S1      
317P3V3_B2_QSFP     VIA   -    MD0100PA00X-023775Y-018230X0220Y         S0      
327P3V3_B2_QSFP     R45   -2          A01X-023775Y-017921X0280Y0320R090 S1      
327P3V3_B2_QSFP     C27   -1          A01X-017375Y-001650X0280Y0320R180 S1      
317P3V3_B2_QSFP     VIA   -    MD0100PA00X-017030Y-001650X0220Y         S0      
327P3V3_B2_QSFP     R57   -2          A01X-031786Y-000150X0280Y0320     S1      
317P3V3_B2_QSFP     VIA   -    MD0100PA00X-017320Y-005240X0220Y         S0      
327P3V3_B2_QSFP     R60   -2          A01X-017709Y-005235X0280Y0320R180 S1      
317P3V3_B2_QSFP     VIA   -    MD0100PA00X-017380Y-004730X0220Y         S0      
327P3V3_B2_QSFP     FS7   -2          A01X-017715Y-004716X0200Y0230     S1      
317P3V3_B2_QSFP     VIA   -    MD0100PA00X-032130Y-002495X0220Y         S0      
327P3V3_B2_QSFP     R30   -1          A01X-031799Y-002495X0280Y0320     S1      
317P3V3_B2_QSFP     VIA   -    MD0100PA00X-032240Y-003100X0220Y         S0      
327P3V3_B2_QSFP     R32   -1          A01X-031786Y-003090X0280Y0320     S1      
317P3V3_B2_QSFP     VIA   -    MD0100PA00X-030290Y-003790X0220Y    R180 S0      
327P3V3_B2_QSFP     R50   -1          A01X-029926Y-003800X0280Y0320     S1      
317P3V3_B2_QSFP     VIA   -    MD0100PA00X-017020Y-003447X0220Y         S0      
327P3V3_B2_QSFP     R58   -1          A01X-017384Y-003447X0280Y0320R180 S1      
317P3V3_B2_QSFP     VIA   -    MD0100PA00X-032170Y-001363X0220Y    R270 S0      
327P3V3_B2_QSFP     R55   -1          A01X-031791Y-001363X0280Y0320     S1      
317P3V3_B2_QSFP     VIA   -    MD0100PA00X-030230Y-002595X0220Y         S0      
327P3V3_B2_QSFP     R48   -1          A01X-029899Y-002595X0280Y0320     S1      
317P3V3_B2_QSFP     VIA   -    MD0100PA00X-017981Y-002130X0220Y         S0      
317P3V3_B2_QSFP     VIA   -    MD0100PA00X-030230Y-000445X0220Y         S0      
327P3V3_B2_QSFP     R46   -1          A01X-029899Y-000445X0280Y0320     S1      
317P3V3_B2_QSFP     VIA   -    MD0100PA00X-029070Y-000975X0220Y    R180 S0      
327P3V3_B2_QSFP     R52   -1          A01X-029401Y-000975X0280Y0320R180 S1      
317P3V3_B2_QSFP     VIA   -    MD0100PA00X-017901Y+000450X0220Y         S0      
317P3V3_B2_QSFP     VIA   -    MD0100PA00X-017050Y-001000X0220Y         S0      
327P3V3_B2_QSFP     R59   -1          A01X-017394Y-001000X0280Y0320R180 S1      
327P3V3_B2_QSFP     R54   -1          A01X-029414Y-004880X0280Y0320R180 S1      
317P3V3_B2_QSFP     VIA   -    MD0100PA00X-029040Y-004320X0220Y         S0      
327P3V3_B2_QSFP     R56   -1   M      A01X-029414Y-004330X0280Y0320R180 S1      
327P3V3_B2_QSFP     FS6   -1          A01X-017881Y+000100X0200Y0230R090 S1      
327P3V3_B2_QSFP     FS5   -1          A01X-018001Y-002450X0200Y0230R090 S1      
317P3V3_B2_QSFP     VIA   -    MD0100PA00X-032186Y-000150X0220Y         S0      
327P3V3_B2_QSFP     R34   -1          A01X-043896Y-007410X0280Y0320     S1      
317P3V3_B2_QSFP     VIA   -    MD0100PA00X-044196Y-007410X0220Y         S0      
327P3V3_B2_QSFP     R70   -1          A01X-044910Y-006384X0280Y0320R270 S1      
317P3V3_B2_QSFP     VIA   -    MD0100PA00X-044910Y-006084X0220Y    R270 S0      
317P3V3_B2_QSFP     VIA   -    MD0100PA00X-044196Y-005760X0220Y         S0      
327P3V3_B2_QSFP     R68   -1          A01X-043896Y-005760X0280Y0320     S1      
317P3V3_B2_QSFP     VIA   -    MD0100PA00X-044196Y-006310X0220Y         S0      
327P3V3_B2_QSFP     R67   -1          A01X-043896Y-006310X0280Y0320     S1      
327P3V3_B2_QSFP     R64   -1          A01X-043896Y-005210X0280Y0320     S1      
317P3V3_B2_QSFP     VIA   -    MD0100PA00X-044196Y-005210X0220Y         S0      
327P3V3_B2_QSFP     R69   -1          A01X-043896Y-004110X0280Y0320     S1      
317P3V3_B2_QSFP     VIA   -    MD0100PA00X-044196Y-004110X0220Y         S0      
327P3V3_B2_QSFP     R62   -1          A01X-043896Y-003560X0280Y0320     S1      
317P3V3_B2_QSFP     VIA   -    MD0100PA00X-044196Y-003560X0220Y         S0      
317P3V3_B2_QSFP     J19   -D5   D0200PA00X-031906Y-016205X0320Y    R180 S3      
317P3V3_B2_QSFP     J19   -E5   D0200PA00X-031906Y-015654X0320Y    R180 S3      
317P3V3_B2_QSFP     J19   -I3   D0200PA00X-030331Y-013449X0320Y    R180 S3      
317P3V3_B2_QSFP     VIA   -    MD0100PA00X-020610Y-017660X0220Y    R180 S0      
317P3V3_B2_QSFP     VIA   -    MD0100PA00X-020160Y-017660X0220Y    R180 S0      
317P3V3_B2_QSFP     VIA   -    MD0100PA00X-019690Y-017650X0220Y    R180 S0      
327P3V3_B1_QSFP     FS1   -1          A01X-113131Y-017990X0200Y0230R090 S1      
327P3V3_B1_QSFP     FS2   -2          A01X-108849Y-017970X0200Y0230R090 S1      
317P3V3_B1_QSFP     J7    -I3   D0200PA00X-117339Y-013449X0320Y    R180 S3      
317P3V3_B1_QSFP     J7    -E5   D0200PA00X-118913Y-015654X0320Y    R180 S3      
317P3V3_B1_QSFP     J7    -D5   D0200PA00X-118913Y-016205X0320Y    R180 S3      
317P3V3_B1_QSFP     VIA   -    MD0100PA00X-110783Y-018230X0220Y         S0      
327P3V3_B1_QSFP     R17   -2          A01X-110783Y-017921X0280Y0320R090 S1      
317P3V3_B1_QSFP     VIA   -    MD0100PA00X-111333Y-018221X0220Y         S0      
327P3V3_B1_QSFP     R13   -1          A01X-111333Y-017921X0280Y0320R090 S1      
317P3V3_B1_QSFP     VIA   -    MD0100PA00X-108460Y-017985X0220Y    R180 S0      
317P3V3_B1_QSFP     VIA   -    MD0100PA00X-113458Y-017985X0220Y    R180 S0      
327P3V3_B1_QSFP     C39   -1          A01X-104555Y-001660X0280Y0320R180 S1      
317P3V3_B1_QSFP     VIA   -    MD0100PA00X-104130Y-001650X0220Y         S0      
327P3V3_B1_QSFP     R29   -2          A01X-118736Y+000000X0280Y0320     S1      
317P3V3_B1_QSFP     VIA   -    MD0100PA00X-119150Y+000000X0220Y         S0      
327P3V3_B1_QSFP     R18   -1          A01X-116849Y-000545X0280Y0320     S1      
317P3V3_B1_QSFP     VIA   -    MD0100PA00X-117210Y-000540X0220Y         S0      
327P3V3_B1_QSFP     FS8   -1          A01X-105091Y-002300X0200Y0230R090 S1      
317P3V3_B1_QSFP     VIA   -    MD0100PA00X-105140Y-002600X0220Y         S0      
327P3V3_B1_QSFP     R6    -1          A01X-130756Y-007420X0280Y0320     S1      
317P3V3_B1_QSFP     VIA   -    MD0100PA00X-131056Y-007420X0220Y         S0      
327P3V3_B1_QSFP     R84   -1          A01X-131770Y-006906X0280Y0320R090 S1      
317P3V3_B1_QSFP     VIA   -    MD0100PA00X-131770Y-007270X0220Y         S0      
317P3V3_B1_QSFP     VIA   -    MD0100PA00X-109340Y-009020X0220Y         S0      
317P3V3_B1_QSFP     VIA   -    MD0100PA00X-107300Y-009030X0220Y         S0      
317P3V3_B1_QSFP     VIA   -    MD0100PA00X-109940Y-009020X0220Y         S0      
327P3V3_B1_QSFP     R82   -1          A01X-130756Y-005770X0280Y0320     S1      
317P3V3_B1_QSFP     VIA   -    MD0100PA00X-131056Y-005770X0220Y         S0      
317P3V3_B1_QSFP     VIA   -    MD0100PA00X-131056Y-006320X0220Y         S0      
327P3V3_B1_QSFP     R81   -1          A01X-130756Y-006320X0280Y0320     S1      
327P3V3_B1_QSFP     R76   -1          A01X-130756Y-005220X0280Y0320     S1      
317P3V3_B1_QSFP     VIA   -    MD0100PA00X-131056Y-005220X0220Y         S0      
327P3V3_B1_QSFP     R28   -1   M      A01X-116344Y-004400X0280Y0320R180 S1      
317P3V3_B1_QSFP     VIA   -    MD0100PA00X-115970Y-004390X0220Y         S0      
327P3V3_B1_QSFP     R26   -1          A01X-116344Y-004950X0280Y0320R180 S1      
317P3V3_B1_QSFP     VIA   -    MD0100PA00X-104430Y-004766X0220Y         S0      
317P3V3_B1_QSFP     VIA   -    MD0100PA00X-119080Y-002345X0220Y         S0      
327P3V3_B1_QSFP     R24   -1          A01X-118749Y-002345X0280Y0320     S1      
327P3V3_B1_QSFP     R4    -1          A01X-118736Y-002940X0280Y0320     S1      
317P3V3_B1_QSFP     VIA   -    MD0100PA00X-119190Y-002950X0220Y         S0      
327P3V3_B1_QSFP     R2    -1          A01X-116344Y-003300X0280Y0320R180 S1      
317P3V3_B1_QSFP     VIA   -    MD0100PA00X-115980Y-003310X0220Y         S0      
327P3V3_B1_QSFP     R72   -1          A01X-104544Y-003400X0280Y0320R180 S1      
317P3V3_B1_QSFP     VIA   -    MD0100PA00X-104540Y-003800X0220Y         S0      
317P3V3_B1_QSFP     VIA   -    MD0100PA00X-119120Y-001213X0220Y    R270 S0      
327P3V3_B1_QSFP     R27   -1          A01X-118741Y-001213X0280Y0320     S1      
327P3V3_B1_QSFP     R22   -1          A01X-116849Y-002695X0280Y0320     S1      
317P3V3_B1_QSFP     VIA   -    MD0100PA00X-117180Y-002695X0220Y         S0      
327P3V3_B1_QSFP     R20   -1          A01X-116849Y-001625X0280Y0320     S1      
317P3V3_B1_QSFP     VIA   -    MD0100PA00X-117180Y-001625X0220Y         S0      
327P3V3_B1_QSFP     FS9   -1          A01X-105081Y+000000X0200Y0230R090 S1      
317P3V3_B1_QSFP     VIA   -    MD0100PA00X-105081Y+000260X0220Y         S0      
327P3V3_B1_QSFP     R73   -1          A01X-104544Y-001000X0280Y0320R180 S1      
317P3V3_B1_QSFP     VIA   -    MD0100PA00X-104130Y-001010X0220Y         S0      
327P3V3_B1_QSFP     FS10  -2          A01X-104800Y-004761X0200Y0230     S1      
317P3V3_B1_QSFP     VIA   -    MD0100PA00X-104510Y-005290X0220Y         S0      
327P3V3_B1_QSFP     R74   -2          A01X-104867Y-005285X0280Y0320R180 S1      
327P3V3_B1_QSFP     R83   -1          A01X-130756Y-004120X0280Y0320     S1      
317P3V3_B1_QSFP     VIA   -    MD0100PA00X-131056Y-004120X0220Y         S0      
317P3V3_B1_QSFP     VIA   -    MD0100PA00X-131056Y-003570X0220Y         S0      
327P3V3_B1_QSFP     R78   -1          A01X-130756Y-003570X0280Y0320     S1      
327m0156            C23   -1          A01X-019010Y-003335X0280Y0320R270 S1      
317m0156            VIA   -    MD0100PA00X-018290Y-002980X0220Y         S0      
327m0156            C19   -1          A01X-018415Y-003455X0200Y0230     S1      
327m0156            FB5   -2          A01X-017995Y-002985X0200Y0230R270 S1      
327m0156            R58   -2          A01X-017896Y-003447X0280Y0320     S1      
317m0156            VIA   -    M      A01X-019030Y-002890X0220Y         S2      
017m0156            VIA   -    M      A08X-019030Y-002890X0320Y         S2      
017m0156                  -    MD0100PA00X-019030Y-002890                       
317m0156            VIA   -    MD0100PA00X-037421Y-017800X0220Y         S0      
327m0156            J20   -29         A01X-037421Y-017260X0140Y0710R180 S1      
327m0157            R59   -2          A01X-017906Y-001000X0280Y0320     S1      
327m0157            C20   -1          A01X-018415Y-000905X0200Y0230     S1      
327m0157            FB6   -2          A01X-017880Y-000450X0200Y0230R270 S1      
317m0157            VIA   -    M      A01X-019030Y-000420X0220Y         S2      
017m0157            VIA   -    M      A08X-019030Y-000420X0320Y         S2      
017m0157                  -    MD0100PA00X-019030Y-000420                       
317m0157            VIA   -    MD0100PA00X-018320Y-000460X0220Y         S0      
317m0157            VIA   -    MD0100PA00X-037580Y-015400X0220Y         S0      
327m0157            C24   -1          A01X-019040Y-000875X0280Y0320R270 S1      
327m0157            J20   -10         A01X-037579Y-016276X0140Y0710R180 S1      
327m0158            C17   -1          A01X-018765Y-005215X0200Y0230R180 S1      
327m0158            FB7   -1          A01X-018265Y-004715X0200Y0230R180 S1      
327m0158            R60   -1          A01X-018221Y-005235X0280Y0320     S1      
317m0158            VIA   -    M      A01X-019100Y-005640X0220Y         S2      
017m0158            VIA   -    M      A08X-019100Y-005640X0320Y         S2      
017m0158                  -    MD0100PA00X-019100Y-005640                       
317m0158            VIA   -    MD0100PA00X-018590Y-005620X0220Y         S0      
327m0158            C18   -1          A01X-019235Y-005290X0280Y0320R090 S1      
317m0158            VIA   -    MD0100PA00X-037106Y-017900X0220Y         S0      
327m0158            J20   -30         A01X-037106Y-017260X0140Y0710R180 S1      
317m0159            VIA   -    MD0100PA00X-106200Y-002920X0220Y         S0      
317m0159            VIA   -           A01X-105490Y-002980X0220Y         S2      
017m0159            VIA   -           A08X-105490Y-002980X0320Y         S2      
017m0159                  -     D0100PA00X-105490Y-002980                       
327m0159            C31   -1          A01X-105600Y-003370X0200Y0230     S1      
327m0159            FB8   -2          A01X-105080Y-002940X0200Y0230R270 S1      
327m0159            R72   -2          A01X-105056Y-003400X0280Y0320     S1      
317m0159            VIA   -    MD0100PA00X-110780Y-006820X0220Y         S0      
327m0159            C35   -1          A01X-106190Y-003305X0280Y0320R270 S1      
317m0159            VIA   -    MD0100PA00X-124429Y-017800X0220Y         S0      
327m0159            J8    -29         A01X-124429Y-017260X0140Y0710R180 S1      
317m0160            VIA   -    MD0100PA00X-106190Y-000520X0220Y         S0      
317m0160            VIA   -           A01X-105460Y-000510X0220Y         S2      
017m0160            VIA   -           A08X-105460Y-000510X0320Y         S2      
017m0160                  -     D0100PA00X-105460Y-000510                       
327m0160            C32   -1          A01X-105600Y-000970X0200Y0230     S1      
327m0160            FB9   -2          A01X-105080Y-000540X0200Y0230R270 S1      
327m0160            R73   -2          A01X-105056Y-001000X0280Y0320     S1      
317m0160            VIA   -    MD0100PA00X-110770Y-006310X0220Y         S0      
317m0160            VIA   -    MD0100PA00X-124639Y-015349X0220Y         S0      
327m0160            C36   -1          A01X-106200Y-000945X0280Y0320R270 S1      
327m0160            J8    -10         A01X-124587Y-016276X0140Y0710R180 S1      
317m0161            VIA   -    MD0100PA00X-106360Y-005660X0220Y         S0      
317m0161            VIA   -           A01X-105690Y-005630X0220Y         S2      
017m0161            VIA   -           A08X-105690Y-005630X0320Y         S2      
017m0161                  -     D0100PA00X-105690Y-005630                       
327m0161            C29   -1          A01X-105923Y-005265X0200Y0230R180 S1      
327m0161            FB10  -1          A01X-105423Y-004765X0200Y0230R180 S1      
327m0161            R74   -1          A01X-105379Y-005285X0280Y0320     S1      
317m0161            VIA   -    MD0100PA00X-110770Y-007340X0220Y         S0      
327m0161            C30   -1          A01X-106393Y-005340X0280Y0320R090 S1      
317m0161            VIA   -    MD0100PA00X-124114Y-017900X0220Y         S0      
327m0161            J8    -30         A01X-124114Y-017260X0140Y0710R180 S1      
327m0162            C10   -1          A01X-023255Y-017515X0200Y0230R090 S1      
327m0162            R45   -1          A01X-023775Y-017409X0280Y0320R270 S1      
327m0162            C9    -1          A01X-023255Y-017065X0200Y0230R090 S1      
317m0162            VIA   -    MD0100PA00X-023690Y-017070X0220Y         S0      
327m0162            FB4   -1          A01X-023255Y-017965X0200Y0230R090 S1      
317m0162            VIA   -    MD0100PA00X-024030Y-012930X0220Y         S0      
327m0162            J17   -16         A01X-024075Y-014236X0200Y0790R180 S1      
327m0163            C12   -1          A01X-024845Y-017515X0200Y0230R270 S1      
327m0163            R41   -2          A01X-024325Y-017409X0280Y0320R270 S1      
327m0163            C11   -1          A01X-024845Y-017065X0200Y0230R270 S1      
317m0163            VIA   -    MD0100PA00X-024490Y-017070X0220Y         S0      
327m0163            FB3   -2          A01X-024810Y-018000X0200Y0230R090 S1      
317m0163            VIA   -    MD0100PA00X-024430Y-012930X0220Y         S0      
327m0163            J17   -15         A01X-024390Y-014236X0200Y0790R180 S1      
327m0164            R17   -1          A01X-110783Y-017409X0280Y0320R270 S1      
327m0164            FB2   -1          A01X-110263Y-017965X0200Y0230R090 S1      
327m0164            C6    -1          A01X-110263Y-017515X0200Y0230R090 S1      
327m0164            C5    -1          A01X-110263Y-017065X0200Y0230R090 S1      
317m0164            VIA   -    MD0100PA00X-110698Y-017070X0220Y         S0      
317m0164            VIA   -    MD0100PA00X-111050Y-012900X0220Y         S0      
327m0164            J5    -16         A01X-111083Y-014236X0200Y0790R180 S1      
327m0165            R13   -2          A01X-111333Y-017409X0280Y0320R270 S1      
327m0165            FB1   -2          A01X-111820Y-018000X0200Y0230R090 S1      
327m0165            C8    -1          A01X-111853Y-017515X0200Y0230R270 S1      
327m0165            C7    -1          A01X-111853Y-017065X0200Y0230R270 S1      
317m0165            VIA   -    MD0100PA00X-111498Y-017070X0220Y         S0      
317m0165            VIA   -    MD0100PA00X-111450Y-012900X0220Y         S0      
327m0165            J5    -15         A01X-111398Y-014236X0200Y0790R180 S1      
327P12V_MEZZ_B2     J14   -137        A01X-062411Y-008439X0250Y    R090 S1      
327P12V_MEZZ_B2     J14   -145        A01X-062411Y-007939X0250Y    R090 S1      
327P12V_MEZZ_B2     J14   -153        A01X-062411Y-007439X0250Y    R090 S1      
327P12V_MEZZ_B2     J14   -154        A01X-061911Y-007439X0250Y    R090 S1      
327P12V_MEZZ_B2     J14   -155        A01X-061411Y-007439X0250Y    R090 S1      
317P12V_MEZZ_B2     J13   -I10  D0200PA00X-074591Y-013449X0320Y    R180 S3      
317P12V_MEZZ_B2     J13   -J10  D0200PA00X-074591Y-012898X0320Y    R180 S3      
317P12V_MEZZ_B2     J13   -K10  D0200PA00X-074591Y-012346X0320Y    R180 S3      
317P12V_MEZZ_B2     J13   -L10  D0200PA00X-074591Y-011795X0320Y    R180 S3      
317P12V_MEZZ_B2     J13   -N10  D0200PA00X-074591Y-010693X0320Y    R180 S3      
317P12V_MEZZ_B2     J13   -O10  D0200PA00X-074591Y-010142X0320Y    R180 S3      
317P12V_MEZZ_B2     VIA   -    MD0100PA00X-061661Y-007189X0220Y         S0      
317P12V_MEZZ_B2     VIA   -    MD0100PA00X-062161Y-007189X0220Y         S0      
317P12V_MEZZ_B2     VIA   -    MD0100PA00X-062661Y-007189X0220Y         S0      
317P12V_MEZZ_B2     VIA   -    MD0100PA00X-062661Y-007689X0220Y         S0      
317P12V_MEZZ_B2     VIA   -    MD0100PA00X-062662Y-008161X0220Y         S0      
317P12V_MEZZ_B1     VIA   -    MD0100PA00X-149169Y-007189X0220Y         S0      
317P12V_MEZZ_B1     VIA   -    MD0100PA00X-148669Y-007189X0220Y         S0      
317P12V_MEZZ_B1     VIA   -    MD0100PA00X-149669Y-007189X0220Y         S0      
317P12V_MEZZ_B1     J1    -J10  D0200PA00X-161598Y-012898X0320Y    R180 S3      
317P12V_MEZZ_B1     J1    -K10  D0200PA00X-161598Y-012346X0320Y    R180 S3      
317P12V_MEZZ_B1     J1    -L10  D0200PA00X-161598Y-011795X0320Y    R180 S3      
317P12V_MEZZ_B1     J1    -N10  D0200PA00X-161598Y-010693X0320Y    R180 S3      
317P12V_MEZZ_B1     J1    -O10  D0200PA00X-161598Y-010142X0320Y    R180 S3      
317P12V_MEZZ_B1     J1    -I10  D0200PA00X-161598Y-013449X0320Y    R180 S3      
327P12V_MEZZ_B1     J2    -155        A01X-148419Y-007439X0250Y    R090 S1      
327P12V_MEZZ_B1     J2    -154        A01X-148919Y-007439X0250Y    R090 S1      
327P12V_MEZZ_B1     J2    -153        A01X-149419Y-007439X0250Y    R090 S1      
327P12V_MEZZ_B1     J2    -145        A01X-149419Y-007939X0250Y    R090 S1      
317P12V_MEZZ_B1     VIA   -    MD0100PA00X-149669Y-007689X0220Y         S0      
327P12V_MEZZ_B1     J2    -137        A01X-149419Y-008439X0250Y    R090 S1      
317P12V_MEZZ_B1     VIA   -    MD0100PA00X-149700Y-008170X0220Y         S0      
317P12V             VIA   -    MD0100PA00X-046200Y-007350X0220Y         S0      
317P12V             VIA   -    MD0100PA00X-044813Y-008880X0220Y         S0      
327P12V             C15   -1          A01X-045363Y-008555X0200Y0230R180 S1      
317P12V             VIA   -    MD0100PA00X-045363Y-008830X0220Y         S0      
317P12V             VIA   -    MD0100PA00X-044900Y+000650X0220Y         S0      
317P12V             VIA   -    MD0100PA00X-043100Y+000650X0220Y         S0      
317P12V             VIA   -    MD0100PA00X-131673Y-008920X0220Y         S0      
317P12V             VIA   -    MD0100PA00X-132223Y-008840X0220Y         S0      
317P12V             VIA   -    MD0100PA00X-161000Y-002750X0220Y         S0      
317P12V             VIA   -    MD0100PA00X-161000Y-003250X0220Y         S0      
317P12V             VIA   -    MD0100PA00X-161000Y-003750X0220Y         S0      
317P12V             VIA   -    MD0100PA00X-161500Y-003250X0220Y         S0      
317P12V             VIA   -    MD0100PA00X-161500Y-002750X0220Y         S0      
317P12V             VIA   -    MD0100PA00X-161500Y-003750X0220Y         S0      
317P12V             VIA   -    MD0100PA00X-159500Y-002750X0220Y         S0      
317P12V             VIA   -    MD0100PA00X-159500Y-003250X0220Y         S0      
317P12V             VIA   -    MD0100PA00X-159500Y-003750X0220Y         S0      
317P12V             VIA   -    MD0100PA00X-160500Y-002750X0220Y         S0      
317P12V             VIA   -    MD0100PA00X-160500Y-003250X0220Y         S0      
317P12V             VIA   -    MD0100PA00X-160500Y-003750X0220Y         S0      
317P12V             VIA   -    MD0100PA00X-160000Y-003250X0220Y         S0      
317P12V             VIA   -    MD0100PA00X-160000Y-002750X0220Y         S0      
317P12V             VIA   -    MD0100PA00X-160000Y-003750X0220Y         S0      
317P12V             VIA   -    MD0100PA00X-159000Y-002750X0220Y         S0      
317P12V             VIA   -    MD0100PA00X-159000Y-003250X0220Y         S0      
317P12V             VIA   -    MD0100PA00X-159000Y-003750X0220Y         S0      
317P12V             VIA   -    MD0100PA00X-158500Y-003750X0220Y         S0      
317P12V             VIA   -    MD0100PA00X-158500Y-002750X0220Y         S0      
317P12V             VIA   -    MD0100PA00X-158500Y-003250X0220Y         S0      
317P12V             VIA   -    MD0100PA00X-158000Y-003750X0220Y         S0      
317P12V             VIA   -    MD0100PA00X-158000Y-003250X0220Y         S0      
317P12V             VIA   -    MD0100PA00X-158000Y-002750X0220Y         S0      
317P12V             VIA   -    MD0100PA00X-157000Y-003750X0220Y         S0      
317P12V             VIA   -    MD0100PA00X-157000Y-002750X0220Y         S0      
317P12V             VIA   -    MD0100PA00X-157000Y-003250X0220Y         S0      
317P12V             VIA   -    MD0100PA00X-157500Y-003750X0220Y         S0      
317P12V             VIA   -    MD0100PA00X-157500Y-003250X0220Y         S0      
317P12V             VIA   -    MD0100PA00X-157500Y-002750X0220Y         S0      
317P12V             VIA   -    MD0100PA00X-156500Y-003750X0220Y         S0      
317P12V             VIA   -    MD0100PA00X-156500Y-003250X0220Y         S0      
317P12V             VIA   -    MD0100PA00X-156500Y-002750X0220Y         S0      
317P12V             VIA   -    MD0100PA00X-156000Y-003750X0220Y         S0      
317P12V             VIA   -    MD0100PA00X-156000Y-003250X0220Y         S0      
317P12V             VIA   -    MD0100PA00X-156000Y-002750X0220Y         S0      
317P12V             VIA   -    MD0100PA00X-155000Y-002750X0220Y         S0      
317P12V             VIA   -    MD0100PA00X-155000Y-003250X0220Y         S0      
317P12V             VIA   -    MD0100PA00X-155000Y-003750X0220Y         S0      
317P12V             VIA   -    MD0100PA00X-155500Y-002750X0220Y         S0      
317P12V             VIA   -    MD0100PA00X-155500Y-003250X0220Y         S0      
317P12V             VIA   -    MD0100PA00X-155500Y-003750X0220Y         S0      
317P12V             VIA   -    MD0100PA00X-154500Y-002750X0220Y         S0      
317P12V             VIA   -    MD0100PA00X-154500Y-003250X0220Y         S0      
317P12V             VIA   -    MD0100PA00X-154500Y-003750X0220Y         S0      
317P12V             J4    -3F  MD0300PA00X-129626Y-017504X0540Y         S3      
317P12V             J4    -3E  MD0300PA00X-130413Y-017504X0540Y         S3      
317P12V             J4    -3D  MD0300PA00X-129626Y-016717X0540Y         S3      
317P12V             J4    -3C  MD0300PA00X-130413Y-016717X0540Y         S3      
317P12V             J4    -3B  MD0300PA00X-129626Y-015929X0540Y         S3      
317P12V             J4    -3A  MD0300PA00X-130413Y-015929X0540Y         S3      
317P12V             J4    -2F  MD0300PA00X-129626Y-014354X0540Y         S3      
317P12V             J4    -2E  MD0300PA00X-130413Y-014354X0540Y         S3      
317P12V             J4    -2D  MD0300PA00X-129626Y-013567X0540Y         S3      
317P12V             J4    -2C  MD0300PA00X-130413Y-013567X0540Y         S3      
317P12V             J4    -2B  MD0300PA00X-129626Y-012780X0540Y         S3      
317P12V             J4    -2A  MD0300PA00X-130413Y-012780X0540Y         S3      
327P12V             C4    -1   M      A01X-132223Y-008565X0200Y0230R180 S1      
317P12V             J16   -3F  MD0300PA00X-042618Y-017504X0540Y         S3      
317P12V             J16   -3E  MD0300PA00X-043406Y-017504X0540Y         S3      
317P12V             J16   -3D  MD0300PA00X-042618Y-016717X0540Y         S3      
317P12V             J16   -3C  MD0300PA00X-043406Y-016717X0540Y         S3      
317P12V             J16   -3B  MD0300PA00X-042618Y-015929X0540Y         S3      
317P12V             J16   -3A  MD0300PA00X-043406Y-015929X0540Y         S3      
317P12V             J16   -2F  MD0300PA00X-042618Y-014354X0540Y         S3      
317P12V             J16   -2E  MD0300PA00X-043406Y-014354X0540Y         S3      
317P12V             J16   -2D  MD0300PA00X-042618Y-013567X0540Y         S3      
317P12V             J16   -2C  MD0300PA00X-043406Y-013567X0540Y         S3      
317P12V             J16   -2B  MD0300PA00X-042618Y-012780X0540Y         S3      
317P12V             J16   -2A  MD0300PA00X-043406Y-012780X0540Y         S3      
317P12V             VIA   -    MD0100PA00X-141239Y-004039X0220Y         S0      
317P12V             VIA   -    MD0100PA00X-141239Y-004539X0220Y         S0      
317P12V             VIA   -    MD0100PA00X-141239Y-005039X0220Y         S0      
317P12V             VIA   -    MD0100PA00X-142739Y-004039X0220Y         S0      
317P12V             VIA   -    MD0100PA00X-142739Y-004539X0220Y         S0      
317P12V             VIA   -    MD0100PA00X-142739Y-005039X0220Y         S0      
317P12V             VIA   -    MD0100PA00X-141989Y-004539X0220Y         S0      
317P12V             VIA   -    MD0100PA00X-141989Y-004039X0220Y         S0      
317P12V             VIA   -    MD0100PA00X-141989Y-005039X0220Y         S0      
317P12V             VIA   -    MD0100PA00X-141239Y-003539X0220Y         S0      
317P12V             VIA   -    MD0100PA00X-142739Y-003539X0220Y         S0      
317P12V             VIA   -    MD0100PA00X-141989Y-003539X0220Y         S0      
317P12V             VIA   -    MD0100PA00X-139739Y-005039X0220Y         S0      
317P12V             VIA   -    MD0100PA00X-139739Y-004539X0220Y         S0      
317P12V             VIA   -    MD0100PA00X-139739Y-004039X0220Y         S0      
317P12V             VIA   -    MD0100PA00X-138989Y-005039X0220Y         S0      
317P12V             VIA   -    MD0100PA00X-138989Y-004539X0220Y         S0      
317P12V             VIA   -    MD0100PA00X-138989Y-004039X0220Y         S0      
317P12V             VIA   -    MD0100PA00X-140489Y-004039X0220Y         S0      
317P12V             VIA   -    MD0100PA00X-140489Y-004539X0220Y         S0      
317P12V             VIA   -    MD0100PA00X-140489Y-005039X0220Y         S0      
317P12V             VIA   -    MD0100PA00X-139739Y-003539X0220Y         S0      
317P12V             VIA   -    MD0100PA00X-138989Y-003539X0220Y         S0      
317P12V             VIA   -    MD0100PA00X-140489Y-003539X0220Y         S0      
317P12V             VIA   -    MD0100PA00X-138239Y-005039X0220Y         S0      
317P12V             VIA   -    MD0100PA00X-138239Y-004539X0220Y         S0      
317P12V             VIA   -    MD0100PA00X-138239Y-004039X0220Y         S0      
317P12V             VIA   -    MD0100PA00X-138239Y-003539X0220Y         S0      
317P12V             VIA   -    MD0100PA00X-145000Y-017500X0220Y         S0      
317P12V             VIA   -    MD0100PA00X-145000Y-015000X0220Y         S0      
317P12V             VIA   -    MD0100PA00X-145000Y-012500X0220Y         S0      
317P12V             VIA   -    MD0100PA00X-145000Y-010000X0220Y         S0      
317P12V             VIA   -    MD0100PA00X-143750Y-016250X0220Y         S0      
317P12V             VIA   -    MD0100PA00X-142500Y-008750X0220Y         S0      
317P12V             VIA   -    MD0100PA00X-139100Y-009650X0220Y         S0      
317P12V             VIA   -    MD0100PA00X-142500Y-006250X0220Y         S0      
317P12V             VIA   -    MD0100PA00X-142500Y-017500X0220Y         S0      
317P12V             VIA   -    MD0100PA00X-144350Y-009400X0220Y         S0      
317P12V             VIA   -    MD0100PA00X-142450Y-010000X0220Y         S0      
317P12V             VIA   -    MD0100PA00X-141250Y-007500X0220Y         S0      
317P12V             VIA   -    MD0100PA00X-141250Y-016250X0220Y         S0      
317P12V             VIA   -    MD0100PA00X-140000Y-017500X0220Y         S0      
317P12V             VIA   -    MD0100PA00X-140000Y-015000X0220Y         S0      
317P12V             VIA   -    MD0100PA00X-141200Y-008700X0220Y         S0      
317P12V             VIA   -    MD0100PA00X-140000Y-012500X0220Y         S0      
317P12V             VIA   -    MD0100PA00X-140050Y-008700X0220Y         S0      
317P12V             VIA   -    MD0100PA00X-138750Y-007500X0220Y         S0      
317P12V             VIA   -    MD0100PA00X-140000Y-006250X0220Y         S0      
317P12V             VIA   -    MD0100PA00X-138750Y-016250X0220Y         S0      
317P12V             VIA   -    MD0100PA00X-138750Y-013750X0220Y         S0      
317P12V             VIA   -    MD0100PA00X-138750Y-011250X0220Y         S0      
317P12V             VIA   -    MD0100PA00X-137500Y-006250X0220Y         S0      
317P12V             VIA   -    MD0100PA00X-136250Y-007500X0220Y         S0      
317P12V             VIA   -    MD0100PA00X-135000Y-006250X0220Y         S0      
317P12V             VIA   -    M      A01X-133540Y-007500X0220Y         S2      
017P12V             VIA   -    M      A08X-133540Y-007500X0320Y         S2      
017P12V                   -    MD0100PA00X-133540Y-007500                       
317P12V             VIA   -    MD0100PA00X-125750Y-004500X0220Y         S0      
317P12V             VIA   -    MD0100PA00X-125750Y-002000X0220Y         S0      
317P12V             VIA   -    MD0100PA00X-129350Y-008000X0220Y         S0      
317P12V             VIA   -    MD0100PA00X-123250Y-002000X0220Y         S0      
317P12V             VIA   -    MD0100PA00X-113750Y-001500X0220Y         S0      
317P12V             VIA   -    MD0100PA00X-111150Y-001500X0220Y         S0      
317P12V             VIA   -    MD0100PA00X-112600Y-000250X0220Y         S0      
317P12V             VIA   -    MD0100PA00X-110000Y-000250X0220Y         S0      
317P12V             VIA   -    MD0100PA00X-092250Y-000750X0220Y         S0      
317P12V             VIA   -    MD0100PA00X-091000Y-004500X0220Y         S0      
317P12V             VIA   -    MD0100PA00X-089750Y-000750X0220Y         S0      
317P12V             VIA   -    MD0100PA00X-091000Y-002000X0220Y         S0      
317P12V             VIA   -    MD0100PA00X-091000Y+000500X0220Y         S0      
317P12V             VIA   -    MD0100PA00X-088500Y-004500X0220Y         S0      
317P12V             VIA   -    MD0100PA00X-088500Y-002000X0220Y         S0      
317P12V             VIA   -    MD0100PA00X-088500Y+000500X0220Y         S0      
317P12V             VIA   -    MD0100PA00X-087250Y-000750X0220Y         S0      
317P12V             VIA   -    M      A01X-086000Y-004500X0220Y         S2      
017P12V             VIA   -    M      A08X-086000Y-004500X0320Y         S2      
017P12V                   -    MD0100PA00X-086000Y-004500                       
317P12V             VIA   -    MD0100PA00X-086000Y-002000X0220Y         S0      
317P12V             VIA   -    MD0100PA00X-086000Y+000500X0220Y         S0      
317P12V             VIA   -    MD0100PA00X-083500Y-004500X0220Y         S0      
317P12V             VIA   -    MD0100PA00X-083500Y-002000X0220Y         S0      
317P12V             VIA   -    MD0100PA00X-084750Y-000750X0220Y         S0      
317P12V             VIA   -    MD0100PA00X-082250Y-000750X0220Y         S0      
317P12V             VIA   -    MD0100PA00X-081000Y-002000X0220Y         S0      
317P12V             VIA   -    MD0100PA00X-081000Y+000500X0220Y         S0      
317P12V             VIA   -    MD0100PA00X-078500Y-002000X0220Y         S0      
317P12V             VIA   -    MD0100PA00X-079750Y-000750X0220Y         S0      
317P12V             VIA   -    MD0100PA00X-078500Y+000500X0220Y         S0      
317P12V             VIA   -    MD0100PA00X-077250Y-000750X0220Y         S0      
317P12V             VIA   -    MD0100PA00X-076000Y-004500X0220Y         S0      
317P12V             VIA   -    MD0100PA00X-076000Y-002000X0220Y         S0      
317P12V             VIA   -    MD0100PA00X-076000Y+000500X0220Y         S0      
317P12V             VIA   -    MD0100PA00X-073500Y-004500X0220Y         S0      
317P12V             VIA   -    MD0100PA00X-073500Y-002000X0220Y         S0      
317P12V             VIA   -    MD0100PA00X-074750Y-000750X0220Y         S0      
317P12V             VIA   -    MD0100PA00X-073500Y+000500X0220Y         S0      
317P12V             VIA   -    MD0100PA00X-072250Y-000750X0220Y         S0      
317P12V             VIA   -    MD0100PA00X-071000Y-004500X0220Y         S0      
317P12V             VIA   -    MD0100PA00X-071000Y-002000X0220Y         S0      
317P12V             VIA   -    MD0100PA00X-071000Y+000500X0220Y         S0      
317P12V             VIA   -    M      A01X-068500Y-004500X0220Y         S2      
017P12V             VIA   -    M      A08X-068500Y-004500X0320Y         S2      
017P12V                   -    MD0100PA00X-068500Y-004500                       
317P12V             VIA   -    MD0100PA00X-068500Y-002000X0220Y         S0      
317P12V             VIA   -    MD0100PA00X-069750Y-000750X0220Y         S0      
317P12V             VIA   -    MD0100PA00X-068500Y+000500X0220Y         S0      
317P12V             VIA   -    MD0100PA00X-067250Y-000750X0220Y         S0      
317P12V             VIA   -    MD0100PA00X-057750Y-016500X0220Y         S0      
317P12V             VIA   -    MD0100PA00X-057750Y-014000X0220Y         S0      
317P12V             VIA   -    M      A01X-057750Y-011500X0220Y         S2      
017P12V             VIA   -    M      A08X-057750Y-011500X0320Y         S2      
017P12V                   -    MD0100PA00X-057750Y-011500                       
317P12V             VIA   -    MD0100PA00X-064250Y-001250X0220Y         S0      
317P12V             VIA   -    MD0100PA00X-057750Y-006500X0220Y         S0      
317P12V             VIA   -    MD0100PA00X-056500Y-017750X0220Y         S0      
317P12V             VIA   -    MD0100PA00X-055250Y-016500X0220Y         S0      
317P12V             VIA   -    MD0100PA00X-055250Y-014000X0220Y         S0      
317P12V             VIA   -    MD0100PA00X-056500Y-015250X0220Y         S0      
317P12V             VIA   -    MD0100PA00X-065550Y-002550X0220Y         S0      
317P12V             VIA   -    MD0100PA00X-061600Y-002550X0220Y         S0      
317P12V             VIA   -    MD0100PA00X-064250Y-003750X0220Y         S0      
317P12V             VIA   -    MD0100PA00X-063000Y-003750X0220Y         S0      
317P12V             VIA   -    MD0100PA00X-064250Y-002550X0220Y         S0      
317P12V             VIA   -    MD0100PA00X-055250Y-006500X0220Y         S0      
317P12V             VIA   -    MD0100PA00X-054000Y-017750X0220Y         S0      
317P12V             VIA   -    MD0100PA00X-054000Y-015250X0220Y         S0      
317P12V             VIA   -    MD0100PA00X-054000Y-012750X0220Y         S0      
317P12V             VIA   -    MD0100PA00X-054000Y-010250X0220Y         S0      
317P12V             VIA   -    MD0100PA00X-054000Y-007750X0220Y         S0      
317P12V             VIA   -    MD0100PA00X-052750Y-016500X0220Y         S0      
317P12V             VIA   -    MD0100PA00X-052750Y-014000X0220Y         S0      
317P12V             VIA   -    MD0100PA00X-052750Y-011500X0220Y         S0      
317P12V             VIA   -    MD0100PA00X-052750Y-009000X0220Y         S0      
317P12V             VIA   -    MD0100PA00X-052750Y-006500X0220Y         S0      
317P12V             VIA   -    MD0100PA00X-051500Y-017750X0220Y         S0      
317P12V             VIA   -    MD0100PA00X-051500Y-015250X0220Y         S0      
317P12V             VIA   -    MD0100PA00X-051500Y-012750X0220Y         S0      
317P12V             VIA   -    MD0100PA00X-051500Y-010250X0220Y         S0      
317P12V             VIA   -    MD0100PA00X-050250Y-009000X0220Y         S0      
317P12V             VIA   -    MD0100PA00X-051500Y-007750X0220Y         S0      
317P12V             VIA   -    MD0100PA00X-050250Y-006500X0220Y         S0      
317P12V             VIA   -    MD0100PA00X-049000Y-010250X0220Y         S0      
317P12V             VIA   -    MD0100PA00X-049000Y-007750X0220Y         S0      
317P12V             VIA   -    MD0100PA00X-057750Y-002500X0220Y         S0      
317P12V             VIA   -    MD0100PA00X-057750Y+000000X0220Y         S0      
317P12V             VIA   -    MD0100PA00X-056500Y-003750X0220Y         S0      
317P12V             VIA   -    MD0100PA00X-056500Y-001250X0220Y         S0      
317P12V             VIA   -    MD0100PA00X-054000Y-003750X0220Y         S0      
317P12V             VIA   -    MD0100PA00X-055250Y-002500X0220Y         S0      
317P12V             VIA   -    MD0100PA00X-054000Y-001250X0220Y         S0      
317P12V             VIA   -    MD0100PA00X-055250Y+000000X0220Y         S0      
317P12V             VIA   -    MD0100PA00X-052750Y-002500X0220Y         S0      
317P12V             VIA   -    MD0100PA00X-052750Y+000000X0220Y         S0      
317P12V             VIA   -    MD0100PA00X-051500Y-003750X0220Y         S0      
317P12V             VIA   -    MD0100PA00X-051500Y-001250X0220Y         S0      
317P12V             VIA   -    MD0100PA00X-050250Y-002500X0220Y         S0      
317P12V             VIA   -    MD0100PA00X-050250Y+000000X0220Y         S0      
317P12V             VIA   -    MD0100PA00X-056500Y+001250X0220Y         S0      
317P12V             VIA   -    MD0100PA00X-054000Y+001250X0220Y         S0      
317P12V             VIA   -    MD0100PA00X-051500Y+001250X0220Y         S0      
317P12V             VIA   -    MD0100PA00X-060250Y-002500X0220Y         S0      
317P12V             VIA   -    MD0100PA00X-060250Y+000000X0220Y         S0      
317P12V             VIA   -    MD0100PA00X-059000Y-003750X0220Y         S0      
317P12V             VIA   -    MD0100PA00X-059000Y-001250X0220Y         S0      
317P12V             VIA   -    MD0100PA00X-059000Y+001250X0220Y         S0      
317P12V             VIA   -    MD0100PA00X-049000Y-003750X0220Y         S0      
317P12V             VIA   -    MD0100PA00X-049000Y-001250X0220Y         S0      
317P12V             VIA   -    MD0100PA00X-049000Y+001250X0220Y         S0      
317P12V             VIA   -    MD0100PA00X-047750Y-002500X0220Y         S0      
317P12V             VIA   -    MD0100PA00X-047750Y+000000X0220Y         S0      
317P12V             VIA   -    MD0100PA00X-046500Y-003750X0220Y         S0      
317P12V             VIA   -    MD0100PA00X-046500Y+001250X0220Y         S0      
317P12V             VIA   -    MD0100PA00X-044000Y+001250X0220Y         S0      
317P12V             VIA   -    MD0100PA00X-140750Y+001450X0220Y         S0      
317P12V             VIA   -    MD0100PA00X-138250Y+001450X0220Y         S0      
317P12V             VIA   -    MD0100PA00X-135750Y+001450X0220Y         S0      
317P12V             VIA   -    MD0100PA00X-133250Y+001450X0220Y         S0      
317P12V             VIA   -    MD0100PA00X-130750Y+001450X0220Y         S0      
317P12V             VIA   -    MD0100PA00X-128250Y+001450X0220Y         S0      
317P12V             VIA   -    MD0100PA00X-125750Y+001450X0220Y         S0      
317P12V             VIA   -    MD0100PA00X-123250Y+001450X0220Y         S0      
317P12V             VIA   -    MD0100PA00X-120750Y+001450X0220Y         S0      
317P12V             VIA   -    MD0100PA00X-118250Y+001450X0220Y         S0      
317P12V             VIA   -    MD0100PA00X-115750Y+001450X0220Y         S0      
317P12V             VIA   -    MD0100PA00X-113250Y+001450X0220Y         S0      
317P12V             VIA   -    MD0100PA00X-110750Y+001450X0220Y         S0      
317P12V             VIA   -    MD0100PA00X-107000Y+001450X0220Y         S0      
317P12V             VIA   -    MD0100PA00X-108250Y+001450X0220Y         S0      
317P12V             VIA   -    MD0100PA00X-104500Y+001450X0220Y         S0      
317P12V             VIA   -    MD0100PA00X-102000Y+001450X0220Y         S0      
317P12V             VIA   -    MD0100PA00X-099500Y+001450X0220Y         S0      
317P12V             VIA   -    MD0100PA00X-097000Y+001450X0220Y         S0      
317P12V             VIA   -    MD0100PA00X-094500Y+001450X0220Y         S0      
317P12V             VIA   -    MD0100PA00X-119950Y-000300X0220Y         S0      
317P12V             VIA   -    MD0100PA00X-099750Y-000750X0220Y         S0      
317P12V             VIA   -    MD0100PA00X-094500Y-000750X0220Y         S0      
317P12V             VIA   -    M      A01X-097000Y-000750X0220Y         S2      
017P12V             VIA   -    M      A08X-097000Y-000750X0320Y         S2      
017P12V                   -    MD0100PA00X-097000Y-000750                       
317P12V             VIA   -    MD0100PA00X-143200Y-001800X0220Y         S0      
317P12V             VIA   -    MD0100PA00X-140700Y-001800X0220Y         S0      
317P12V             VIA   -    MD0100PA00X-138250Y-001800X0220Y         S0      
317P12V             VIA   -    MD0100PA00X-133540Y-003760X0220Y         S0      
317P12V             VIA   -    MD0100PA00X-159000Y-004250X0220Y         S0      
317P12V             VIA   -    MD0100PA00X-159000Y-004750X0220Y         S0      
317P12V             VIA   -    MD0100PA00X-158500Y-004750X0220Y         S0      
317P12V             VIA   -    MD0100PA00X-158500Y-004250X0220Y         S0      
317P12V             VIA   -    MD0100PA00X-158000Y-004750X0220Y         S0      
317P12V             VIA   -    MD0100PA00X-158000Y-004250X0220Y         S0      
317P12V             VIA   -    MD0100PA00X-157000Y-004750X0220Y         S0      
317P12V             VIA   -    MD0100PA00X-157000Y-004250X0220Y         S0      
317P12V             VIA   -    MD0100PA00X-157500Y-004750X0220Y         S0      
317P12V             VIA   -    MD0100PA00X-157500Y-004250X0220Y         S0      
317P12V             VIA   -    MD0100PA00X-156500Y-004750X0220Y         S0      
317P12V             VIA   -    MD0100PA00X-156500Y-004250X0220Y         S0      
317P12V             VIA   -    MD0100PA00X-154500Y-004250X0220Y         S0      
317P12V             VIA   -    MD0100PA00X-154500Y-004750X0220Y         S0      
317P12V             VIA   -    MD0100PA00X-156000Y-004750X0220Y         S0      
317P12V             VIA   -    MD0100PA00X-156000Y-004250X0220Y         S0      
317P12V             VIA   -    MD0100PA00X-155000Y-004250X0220Y         S0      
317P12V             VIA   -    MD0100PA00X-155000Y-004750X0220Y         S0      
317P12V             VIA   -    MD0100PA00X-155500Y-004250X0220Y         S0      
317P12V             VIA   -    MD0100PA00X-155500Y-004750X0220Y         S0      
317P12V             VIA   -    MD0100PA00X-154000Y-004750X0220Y         S0      
317P12V             VIA   -    MD0100PA00X-154000Y-004250X0220Y         S0      
317P12V             VIA   -    MD0100PA00X-153500Y-004750X0220Y         S0      
317P12V             VIA   -    MD0100PA00X-153500Y-004250X0220Y         S0      
317P12V             VIA   -    M      A01X-153500Y-003250X0220Y         S2      
017P12V             VIA   -    M      A08X-153500Y-003250X0320Y         S2      
017P12V                   -    MD0100PA00X-153500Y-003250                       
317P12V             VIA   -    MD0100PA00X-153500Y-003750X0220Y         S0      
317P12V             VIA   -    MD0100PA00X-154000Y-003250X0220Y         S0      
317P12V             VIA   -    MD0100PA00X-154000Y-003750X0220Y         S0      
317P12V             VIA   -    MD0100PA00X-092200Y+001450X0220Y         S0      
317P12V             VIA   -    MD0100PA00X-089750Y+001450X0220Y         S0      
317P12V             VIA   -    MD0100PA00X-087250Y+001450X0220Y         S0      
317P12V             VIA   -    MD0100PA00X-084800Y+001450X0220Y         S0      
317P12V             VIA   -    MD0100PA00X-082250Y+001450X0220Y         S0      
317P12V             VIA   -    MD0100PA00X-079750Y+001450X0220Y         S0      
317P12V             VIA   -    MD0100PA00X-077250Y+001450X0220Y         S0      
317P12V             VIA   -    MD0100PA00X-074750Y+001450X0220Y         S0      
317P12V             VIA   -    MD0100PA00X-072250Y+001450X0220Y         S0      
317P12V             VIA   -    MD0100PA00X-069750Y+001450X0220Y         S0      
317P12V             VIA   -    MD0100PA00X-067250Y+001450X0220Y         S0      
317P12V             VIA   -    MD0100PA00X-064500Y+001450X0220Y         S0      
327P12V             C1    -1   M      A01X-131673Y-008590X0280Y0320R090 S1      
327P12V             C13   -1          A01X-044813Y-008580X0280Y0320R090 S1      
327P12V             U1    -P17-       A08X-160071Y+000469X3720Y2480R180 S2      
327P12V             U1    -P21-       A08X-156071Y+000469X3720Y2480R180 S2      
317P12V             J27   -1   MD0550PA00X-078520Y-008310X0790Y0790R270 S3      
317P12V             J27   -3   MD0550PA00X-080685Y-008310X0790Y    R270 S3      
327P12V             C3    -1          A01X-139130Y-013680X0200Y0230R180 S1      
327P12V             C2    -1          A01X-139610Y-013665X0280Y0320R090 S1      
327P12V             U1    -P13-       A01X-160071Y+000469X3720Y2480R180 S1      
327P12V             U1    -P9-P       A01X-156071Y+000469X3720Y2480R180 S1      
317P12V             VIA   -    MD0100PA00X-092250Y-005750X0220Y         S0      
317P12V             VIA   -    MD0100PA00X-089750Y-005750X0220Y         S0      
317P12V             VIA   -    MD0100PA00X-087250Y-005750X0220Y         S0      
317P12V             VIA   -    MD0100PA00X-084750Y-005750X0220Y         S0      
317P12V             VIA   -    MD0100PA00X-082250Y-005750X0220Y         S0      
317P12V             VIA   -    MD0100PA00X-077250Y-005750X0220Y         S0      
317P12V             VIA   -    MD0100PA00X-074750Y-005750X0220Y         S0      
317P12V             VIA   -    MD0100PA00X-072250Y-005750X0220Y         S0      
327P12V             C16   -1          A01X-051920Y-012730X0200Y0230R180 S1      
327P12V             C14   -1          A01X-053550Y-012735X0280Y0320R090 S1      
317P12V             VIA   -    MD0100PA00X-137000Y+000700X0220Y         S0      
317P12V             VIA   -    MD0100PA00X-134500Y+000700X0220Y         S0      
317P12V             VIA   -    MD0100PA00X-132000Y+000700X0220Y         S0      
317P12V             VIA   -    MD0100PA00X-138250Y-000050X0220Y         S0      
317P12V             VIA   -    MD0100PA00X-135750Y-000050X0220Y         S0      
317P12V             VIA   -    MD0100PA00X-133250Y-000050X0220Y         S0      
317P12V             VIA   -    MD0100PA00X-139500Y-000800X0220Y         S0      
317P12V             VIA   -    MD0100PA00X-137000Y-000800X0220Y         S0      
317P12V             VIA   -    MD0100PA00X-134500Y-000800X0220Y         S0      
317P12V             VIA   -    MD0100PA00X-143489Y-004539X0220Y         S0      
317P12V             VIA   -    MD0100PA00X-143489Y-005039X0220Y         S0      
317P12V             VIA   -    MD0100PA00X-143489Y-004039X0220Y         S0      
317P12V             VIA   -    MD0100PA00X-143489Y-003539X0220Y         S0      
317P12V             VIA   -    MD0100PA00X-091000Y-007000X0220Y         S0      
317P12V             VIA   -    MD0100PA00X-088500Y-007000X0220Y         S0      
317P12V             VIA   -    MD0100PA00X-086000Y-007000X0220Y         S0      
317P12V             VIA   -    MD0100PA00X-083500Y-007000X0220Y         S0      
317P12V             VIA   -    MD0100PA00X-076000Y-007000X0220Y         S0      
317P12V             VIA   -    MD0100PA00X-091000Y-009500X0220Y         S0      
317P12V             VIA   -    MD0100PA00X-088500Y-009500X0220Y         S0      
317P12V             VIA   -    MD0100PA00X-086000Y-009500X0220Y         S0      
317P12V             VIA   -    MD0100PA00X-083500Y-009500X0220Y         S0      
317P12V             VIA   -    MD0100PA00X-076000Y-009500X0220Y         S0      
317P12V             VIA   -    MD0100PA00X-083500Y-012000X0220Y         S0      
317P12V             VIA   -    MD0100PA00X-076000Y-012000X0220Y         S0      
317P12V             VIA   -    MD0100PA00X-076000Y-014500X0220Y         S0      
317P12V             VIA   -    MD0100PA00X-091000Y-017000X0220Y         S0      
317P12V             VIA   -    MD0100PA00X-088500Y-017000X0220Y         S0      
317P12V             VIA   -    MD0100PA00X-086000Y-017000X0220Y         S0      
317P12V             VIA   -    MD0100PA00X-092250Y-008250X0220Y         S0      
317P12V             VIA   -    MD0100PA00X-089750Y-008250X0220Y         S0      
317P12V             VIA   -    MD0100PA00X-087250Y-008250X0220Y         S0      
317P12V             VIA   -    MD0100PA00X-084750Y-008250X0220Y         S0      
317P12V             VIA   -    MD0100PA00X-082250Y-008250X0220Y         S0      
317P12V             VIA   -    MD0100PA00X-077250Y-008250X0220Y         S0      
317P12V             VIA   -    MD0100PA00X-092250Y-010750X0220Y         S0      
317P12V             VIA   -    MD0100PA00X-089750Y-010750X0220Y         S0      
317P12V             VIA   -    MD0100PA00X-087250Y-010750X0220Y         S0      
317P12V             VIA   -    MD0100PA00X-084750Y-010750X0220Y         S0      
317P12V             VIA   -    MD0100PA00X-082250Y-010750X0220Y         S0      
317P12V             VIA   -    MD0100PA00X-077250Y-010750X0220Y         S0      
317P12V             VIA   -    MD0100PA00X-092250Y-013250X0220Y         S0      
317P12V             VIA   -    MD0100PA00X-089750Y-013250X0220Y         S0      
317P12V             VIA   -    MD0100PA00X-087250Y-013250X0220Y         S0      
317P12V             VIA   -    MD0100PA00X-084750Y-013250X0220Y         S0      
317P12V             VIA   -    MD0100PA00X-082250Y-013250X0220Y         S0      
317P12V             VIA   -    MD0100PA00X-077250Y-013250X0220Y         S0      
317P12V             VIA   -    MD0100PA00X-092250Y-015950X0220Y         S0      
317P12V             VIA   -    MD0100PA00X-089750Y-015950X0220Y         S0      
317P12V             VIA   -    MD0100PA00X-087250Y-015950X0220Y         S0      
317P12V             VIA   -    MD0100PA00X-084750Y-015950X0220Y         S0      
317P12V             VIA   -    MD0100PA00X-082250Y-015950X0220Y         S0      
317P12V             VIA   -    M      A01X-115150Y-001500X0220Y         S2      
017P12V             VIA   -    M      A08X-115150Y-001500X0320Y         S2      
017P12V                   -    MD0100PA00X-115150Y-001500                       
317P12V             VIA   -    M      A01X-042450Y-002650X0220Y         S2      
017P12V             VIA   -    M      A08X-042450Y-002650X0320Y         S2      
017P12V                   -    MD0100PA00X-042450Y-002650                       
317SERIAL_B1_TX1    J7    -H3   D0200PA00X-117339Y-014000X0320Y    R180 S3      
317SERIAL_B1_TX1    VIA   -    MD0100PA00X-116000Y-011510X0220Y         S0      
317SERIAL_B1_TX1    VIA   -    MD0100PA00X-144910Y-007180X0220Y         S0      
317SERIAL_B1_TX1    VIA   -    MD0100PA00X-102214Y-012296X0220Y         S0      
317SERIAL_B1_TX1    J11   -A3   D0200PA00X-099087Y-017858X0320Y    R180 S3      
327SERIAL_B1_TX1    U1    -S1         A01X-162949Y+000724X0320Y1970R180 S1      
317SERIAL_B1_TX1    VIA   -    MD0100PA00X-162160Y-006110X0220Y         S0      
317SERIAL_B1_RX1    J7    -G3   D0200PA00X-117339Y-014551X0320Y    R180 S3      
317SERIAL_B1_RX1    J11   -B3   D0200PA00X-099087Y-017307X0320Y    R180 S3      
317SERIAL_B1_RX1    VIA   -    MD0100PA00X-101767Y-012325X0220Y         S0      
317SERIAL_B1_RX1    VIA   -    MD0100PA00X-145200Y-007400X0220Y         S0      
327SERIAL_B1_RX1    U1    -S2         A01X-163449Y+000724X0320Y1970R180 S1      
317SERIAL_B1_RX1    VIA   -    MD0100PA00X-161830Y-006310X0220Y         S0      
327m0166            J14   -160        A01X-058911Y-007439X0250Y    R090 S1      
317m0166            VIA   -    MD0100PA00X-059161Y-007189X0220Y         S0      
317m0166            J13   -H6   D0200PA00X-071441Y-014000X0320Y    R180 S3      
327m0167            J2    -160        A01X-145919Y-007439X0250Y    R090 S1      
317m0167            VIA   -    MD0100PA00X-146169Y-007189X0220Y         S0      
317m0167            J1    -H6   D0200PA00X-158449Y-014000X0320Y    R180 S3      
327MEZZ_B2_SDA      J14   -158        A01X-059911Y-007439X0250Y    R090 S1      
317MEZZ_B2_SDA      VIA   -    MD0100PA00X-060161Y-007189X0220Y         S0      
317MEZZ_B2_SDA      J13   -I4   D0200PA00X-069866Y-013449X0320Y    R180 S3      
327MEZZ_B2_SCL      J14   -156        A01X-060911Y-007439X0250Y    R090 S1      
317MEZZ_B2_SCL      VIA   -    MD0100PA00X-061161Y-007189X0220Y         S0      
317MEZZ_B2_SCL      J13   -G5   D0200PA00X-070654Y-014512X0320Y    R180 S3      
327MEZZ_B2_EN       J14   -157        A01X-060411Y-007439X0250Y    R090 S1      
317MEZZ_B2_EN       VIA   -    MD0100PA00X-060661Y-007189X0220Y         S0      
317MEZZ_B2_EN       J13   -H5   D0200PA00X-070654Y-013961X0320Y    R180 S3      
327MEZZ_B1_SDA      J2    -158        A01X-146919Y-007439X0250Y    R090 S1      
317MEZZ_B1_SDA      VIA   -    MD0100PA00X-147169Y-007189X0220Y         S0      
317MEZZ_B1_SDA      J1    -I4   D0200PA00X-156874Y-013449X0320Y    R180 S3      
327MEZZ_B1_SCL      J2    -156        A01X-147919Y-007439X0250Y    R090 S1      
317MEZZ_B1_SCL      VIA   -    MD0100PA00X-148169Y-007189X0220Y         S0      
317MEZZ_B1_SCL      J1    -G5   D0200PA00X-157661Y-014512X0320Y    R180 S3      
327MEZZ_B1_EN       J2    -157        A01X-147419Y-007439X0250Y    R090 S1      
317MEZZ_B1_EN       VIA   -    MD0100PA00X-147669Y-007189X0220Y         S0      
317MEZZ_B1_EN       J1    -H5   D0200PA00X-157661Y-013961X0320Y    R180 S3      
317m0168            J23   -B4   D0200PA00X-012866Y-017346X0320Y    R180 S3      
327m0168            R71   -2          A01X-007840Y-017656X0280Y0320R090 S1      
317m0169            J11   -B4   D0200PA00X-099874Y-017346X0320Y    R180 S3      
327m0169            R1    -2          A01X-094850Y-017556X0280Y0320R090 S1      
317GND              VIA   -    MD0100PA00X-127264Y-017800X0220Y         S0      
327GND              J2    -147        A01X-148419Y-007939X0250Y    R090 S1      
327GND              J14   -147        A01X-061411Y-007939X0250Y    R090 S1      
327GND              J14   -146        A01X-061911Y-007939X0250Y    R090 S1      
327GND              R3    -2   M      A01X-116344Y-003850X0280Y0320R180 S1      
327GND              R12   -2   M      A01X-118244Y-004050X0280Y0320R180 S1      
317GND              VIA   -    MD0100PA00X-117900Y-004050X0220Y         S0      
327GND              R5    -2   M      A01X-118736Y-003490X0280Y0320     S1      
317GND              VIA   -    MD0100PA00X-119150Y-003400X0220Y         S0      
327GND              R25   -2   M      A01X-118749Y-001825X0280Y0320     S1      
317GND              VIA   -    MD0100PA00X-119100Y-001825X0220Y         S0      
327GND              R23   -2   M      A01X-116849Y-002175X0280Y0320     S1      
317GND              VIA   -    MD0100PA00X-117150Y-002175X0220Y         S0      
327GND              R21   -2   M      A01X-116849Y-001075X0280Y0320     S1      
317GND              VIA   -    MD0100PA00X-117200Y-001075X0220Y         S0      
327GND              R11   -2          A01X-135650Y-002116X0280Y0320R090 S1      
317GND              VIA   -    MD0100PA00X-135670Y-002560X0220Y         S0      
327GND              C2    -2          A01X-139610Y-013155X0280Y0320R270 S1      
317GND              VIA   -    MD0100PA00X-140010Y-013155X0220Y         S0      
327GND              C3    -2          A01X-139130Y-013320X0200Y0230R180 S1      
327GND              R86   -1          A01X-064970Y-012536X0280Y0320R090 S1      
317GND              VIA   -    MD0100PA00X-064370Y-012540X0220Y         S0      
327GND              R85   -1          A01X-151900Y-012536X0280Y0320R090 S1      
317GND              VIA   -    M      A01X-152436Y-012536X0220Y         S2      
017GND              VIA   -    M      A08X-152436Y-012536X0320Y         S2      
017GND                    -    MD0100PA00X-152436Y-012536                       
327GND              J14   -33         A01X-062411Y-014939X0250Y    R090 S1      
317GND              VIA   -    MD0100PA00X-062720Y-015130X0220Y         S0      
327GND              J14   -41         A01X-062411Y-014439X0250Y    R090 S1      
317GND              VIA   -    MD0100PA00X-062690Y-014130X0220Y         S0      
327GND              J14   -65         A01X-062411Y-012939X0250Y    R090 S1      
317GND              VIA   -    MD0100PA00X-062870Y-013010X0220Y         S0      
327GND              J14   -73         A01X-062411Y-012439X0250Y    R090 S1      
317GND              VIA   -    MD0100PA00X-062161Y-012189X0220Y    R270 S0      
327GND              C7    -2   M      A01X-112213Y-017065X0200Y0230R270 S1      
317GND              VIA   -    M      A01X-112490Y-017065X0220Y         S2      
017GND              VIA   -    M      A08X-112490Y-017065X0320Y         S2      
017GND                    -    MD0100PA00X-112490Y-017065                       
327GND              C8    -2   M      A01X-112213Y-017515X0200Y0230R270 S1      
317GND              VIA   -    MD0100PA00X-112488Y-017515X0220Y         S0      
327GND              C6    -2   M      A01X-109903Y-017515X0200Y0230R090 S1      
317GND              VIA   -    MD0100PA00X-109620Y-017515X0220Y         S0      
327GND              C5    -2   M      A01X-109903Y-017065X0200Y0230R090 S1      
317GND              VIA   -    M      A01X-109628Y-017065X0220Y         S2      
017GND              VIA   -    M      A08X-109628Y-017065X0320Y         S2      
017GND                    -    MD0100PA00X-109628Y-017065                       
317GND              VIA   -    M      A01X-044444Y-008071X0220Y         S2      
017GND              VIA   -    M      A08X-044444Y-008071X0320Y         S2      
017GND                    -    MD0100PA00X-044444Y-008071                       
327GND              C15   -2   M      A01X-045363Y-008195X0200Y0230R180 S1      
317GND              VIA   -    MD0100PA00X-045624Y-008202X0220Y         S0      
327GND              C10   -2   M      A01X-022895Y-017515X0200Y0230R090 S1      
317GND              VIA   -    MD0100PA00X-022612Y-017515X0220Y         S0      
327GND              C9    -2   M      A01X-022895Y-017065X0200Y0230R090 S1      
317GND              VIA   -    M      A01X-022620Y-017065X0220Y         S2      
017GND              VIA   -    M      A08X-022620Y-017065X0320Y         S2      
017GND                    -    MD0100PA00X-022620Y-017065                       
327GND              C12   -2   M      A01X-025205Y-017515X0200Y0230R270 S1      
317GND              VIA   -    MD0100PA00X-025480Y-017515X0220Y         S0      
327GND              C11   -2   M      A01X-025205Y-017065X0200Y0230R270 S1      
317GND              VIA   -    MD0100PA00X-025480Y-017065X0220Y         S0      
317GND              VIA   -    MD0100PA00X-019039Y+001274X0220Y         S0      
317GND              VIA   -    MD0100PA00X-046144Y+000656X0220Y         S0      
317GND              VIA   -    MD0100PA00X-044394Y+000656X0220Y         S0      
317GND              VIA   -    M      A01X-132484Y-008212X0220Y         S2      
017GND              VIA   -    M      A08X-132484Y-008212X0320Y         S2      
017GND                    -    MD0100PA00X-132484Y-008212                       
317GND              VIA   -    MD0100PA00X-131304Y-008081X0220Y         S0      
317GND              VIA   -    MD0100PA00X-148669Y-016689X0220Y         S0      
317GND              VIA   -    M      A01X-149704Y-016939X0220Y         S2      
017GND              VIA   -    M      A08X-149704Y-016939X0320Y         S2      
017GND                    -    MD0100PA00X-149704Y-016939                       
317GND              VIA   -    MD0100PA00X-149704Y-016439X0220Y         S0      
317GND              VIA   -    MD0100PA00X-147669Y-016689X0220Y         S0      
317GND              VIA   -    MD0100PA00X-146669Y-016689X0220Y         S0      
317GND              VIA   -    MD0100PA00X-149169Y-015689X0220Y         S0      
317GND              VIA   -    MD0100PA00X-149165Y-015185X0220Y         S0      
317GND              VIA   -    MD0100PA00X-148669Y-016189X0220Y         S0      
317GND              VIA   -    MD0100PA00X-149704Y-014939X0220Y         S0      
317GND              VIA   -    MD0100PA00X-146669Y-016189X0220Y         S0      
317GND              VIA   -    MD0100PA00X-147169Y-015689X0220Y         S0      
317GND              VIA   -    MD0100PA00X-147169Y-015189X0220Y         S0      
317GND              VIA   -    MD0100PA00X-148169Y-015189X0220Y         S0      
317GND              VIA   -    MD0100PA00X-148169Y-015689X0220Y         S0      
317GND              VIA   -    MD0100PA00X-147669Y-016189X0220Y         S0      
317GND              VIA   -    MD0100PA00X-146169Y-015689X0220Y         S0      
317GND              VIA   -    MD0100PA00X-146169Y-015189X0220Y         S0      
317GND              VIA   -    MD0100PA00X-148669Y-014689X0220Y         S0      
317GND              VIA   -    MD0100PA00X-148669Y-014189X0220Y         S0      
317GND              VIA   -    MD0100PA00X-149169Y-013689X0220Y         S0      
317GND              VIA   -    MD0100PA00X-149704Y-014439X0220Y         S0      
317GND              VIA   -    MD0100PA00X-147669Y-014689X0220Y         S0      
317GND              VIA   -    MD0100PA00X-146669Y-014689X0220Y         S0      
317GND              VIA   -    MD0100PA00X-147669Y-014189X0220Y         S0      
317GND              VIA   -    MD0100PA00X-146669Y-014189X0220Y         S0      
317GND              VIA   -    MD0100PA00X-147169Y-013689X0220Y         S0      
317GND              VIA   -    MD0100PA00X-148169Y-013689X0220Y         S0      
317GND              VIA   -    MD0100PA00X-146169Y-013689X0220Y         S0      
317GND              VIA   -    MD0100PA00X-149169Y-013189X0220Y         S0      
317GND              VIA   -    MD0100PA00X-148669Y-012689X0220Y         S0      
317GND              VIA   -    MD0100PA00X-148669Y-012189X0220Y         S0      
317GND              VIA   -    MD0100PA00X-149704Y-012939X0220Y         S0      
317GND              VIA   -    MD0100PA00X-149704Y-012439X0220Y         S0      
317GND              VIA   -    MD0100PA00X-147169Y-013189X0220Y         S0      
317GND              VIA   -    MD0100PA00X-147669Y-012689X0220Y         S0      
317GND              VIA   -    MD0100PA00X-146669Y-012689X0220Y         S0      
317GND              VIA   -    MD0100PA00X-147669Y-012189X0220Y         S0      
317GND              VIA   -    MD0100PA00X-146669Y-012189X0220Y         S0      
317GND              VIA   -    MD0100PA00X-148169Y-013189X0220Y         S0      
317GND              VIA   -    MD0100PA00X-146169Y-013189X0220Y         S0      
317GND              VIA   -    MD0100PA00X-149169Y-011689X0220Y         S0      
317GND              VIA   -    MD0100PA00X-149169Y-011189X0220Y         S0      
317GND              VIA   -    MD0100PA00X-148669Y-010689X0220Y         S0      
317GND              VIA   -    MD0100PA00X-148669Y-010189X0220Y         S0      
317GND              VIA   -    MD0100PA00X-149704Y-010439X0220Y         S0      
317GND              VIA   -    MD0100PA00X-149704Y-010939X0220Y         S0      
317GND              VIA   -    MD0100PA00X-147169Y-011689X0220Y         S0      
317GND              VIA   -    MD0100PA00X-147169Y-011189X0220Y         S0      
317GND              VIA   -    MD0100PA00X-147669Y-010689X0220Y         S0      
317GND              VIA   -    MD0100PA00X-146669Y-010689X0220Y         S0      
317GND              VIA   -    MD0100PA00X-147669Y-010189X0220Y         S0      
317GND              VIA   -    MD0100PA00X-146669Y-010189X0220Y         S0      
317GND              VIA   -    MD0100PA00X-148169Y-011689X0220Y         S0      
317GND              VIA   -    MD0100PA00X-148169Y-011189X0220Y         S0      
317GND              VIA   -    MD0100PA00X-146169Y-011689X0220Y         S0      
317GND              VIA   -    MD0100PA00X-146169Y-011189X0220Y         S0      
317GND              VIA   -    MD0100PA00X-149169Y-009689X0220Y         S0      
317GND              VIA   -    MD0100PA00X-149169Y-009189X0220Y         S0      
317GND              VIA   -    MD0100PA00X-148669Y-008689X0220Y         S0      
317GND              VIA   -    MD0100PA00X-149704Y-008939X0220Y         S0      
317GND              VIA   -    MD0100PA00X-147169Y-009689X0220Y         S0      
317GND              VIA   -    MD0100PA00X-147169Y-009189X0220Y         S0      
317GND              VIA   -    MD0100PA00X-147669Y-008689X0220Y         S0      
317GND              VIA   -    MD0100PA00X-146669Y-008689X0220Y         S0      
317GND              VIA   -    MD0100PA00X-148169Y-009689X0220Y         S0      
317GND              VIA   -    MD0100PA00X-148169Y-009189X0220Y         S0      
317GND              VIA   -    MD0100PA00X-146169Y-009689X0220Y         S0      
317GND              VIA   -    MD0100PA00X-146169Y-009189X0220Y         S0      
317GND              VIA   -    MD0100PA00X-148669Y-008189X0220Y         S0      
317GND              VIA   -    MD0100PA00X-149169Y-007689X0220Y         S0      
317GND              VIA   -    MD0100PA00X-147669Y-008189X0220Y         S0      
317GND              VIA   -    M      A01X-153506Y-002216X0220Y         S2      
017GND              VIA   -    M      A08X-153506Y-002216X0320Y         S2      
017GND                    -    MD0100PA00X-153506Y-002216                       
317GND              VIA   -    MD0100PA00X-153506Y-001716X0220Y         S0      
317GND              VIA   -    MD0100PA00X-153506Y-001216X0220Y         S0      
317GND              VIA   -    MD0100PA00X-152006Y-002216X0220Y         S0      
317GND              VIA   -    MD0100PA00X-153006Y-002216X0220Y         S0      
317GND              VIA   -    MD0100PA00X-152506Y-002216X0220Y         S0      
317GND              VIA   -    MD0100PA00X-152006Y-001716X0220Y         S0      
317GND              VIA   -    MD0100PA00X-152006Y-001216X0220Y         S0      
317GND              VIA   -    MD0100PA00X-153006Y-001716X0220Y         S0      
317GND              VIA   -    MD0100PA00X-153006Y-001216X0220Y         S0      
317GND              VIA   -    MD0100PA00X-152506Y-001716X0220Y         S0      
317GND              VIA   -    MD0100PA00X-152506Y-001216X0220Y         S0      
317GND              VIA   -    MD0100PA00X-150506Y-002216X0220Y         S0      
317GND              VIA   -    MD0100PA00X-151506Y-002216X0220Y         S0      
317GND              VIA   -    MD0100PA00X-151006Y-002216X0220Y         S0      
317GND              VIA   -    MD0100PA00X-150506Y-001716X0220Y         S0      
317GND              VIA   -    MD0100PA00X-150506Y-001216X0220Y         S0      
317GND              VIA   -    MD0100PA00X-151506Y-001716X0220Y         S0      
317GND              VIA   -    MD0100PA00X-151506Y-001216X0220Y         S0      
317GND              VIA   -    MD0100PA00X-151006Y-001716X0220Y         S0      
317GND              VIA   -    MD0100PA00X-151006Y-001216X0220Y         S0      
317GND              VIA   -    MD0100PA00X-149006Y-002216X0220Y         S0      
317GND              VIA   -    MD0100PA00X-150006Y-002216X0220Y         S0      
317GND              VIA   -    MD0100PA00X-149506Y-002216X0220Y         S0      
317GND              VIA   -    MD0100PA00X-149006Y-001716X0220Y         S0      
317GND              VIA   -    MD0100PA00X-149006Y-001216X0220Y         S0      
317GND              VIA   -    MD0100PA00X-150006Y-001716X0220Y         S0      
317GND              VIA   -    MD0100PA00X-150006Y-001216X0220Y         S0      
317GND              VIA   -    MD0100PA00X-149506Y-001716X0220Y         S0      
317GND              VIA   -    MD0100PA00X-149506Y-001216X0220Y         S0      
317GND              VIA   -    M      A01X-147506Y-002216X0220Y         S2      
017GND              VIA   -    M      A08X-147506Y-002216X0320Y         S2      
017GND                    -    MD0100PA00X-147506Y-002216                       
317GND              VIA   -    MD0100PA00X-148506Y-002216X0220Y         S0      
317GND              VIA   -    MD0100PA00X-148006Y-002216X0220Y         S0      
317GND              VIA   -    MD0100PA00X-147506Y-001716X0220Y         S0      
317GND              VIA   -    MD0100PA00X-147506Y-001216X0220Y         S0      
317GND              VIA   -    MD0100PA00X-148506Y-001716X0220Y         S0      
317GND              VIA   -    MD0100PA00X-148506Y-001216X0220Y         S0      
317GND              VIA   -    MD0100PA00X-148006Y-001716X0220Y         S0      
317GND              VIA   -    MD0100PA00X-148006Y-001216X0220Y         S0      
317GND              VIA   -    MD0100PA00X-147006Y-002216X0220Y         S0      
317GND              VIA   -    MD0100PA00X-146506Y-002216X0220Y         S0      
317GND              VIA   -    MD0100PA00X-147006Y-001716X0220Y         S0      
317GND              VIA   -    MD0100PA00X-147006Y-001216X0220Y         S0      
317GND              VIA   -    MD0100PA00X-146506Y-001716X0220Y         S0      
317GND              VIA   -    MD0100PA00X-146506Y-001216X0220Y         S0      
317GND              J23   -J6  MD0200PA00X-014441Y-012937X0320Y    R180 S3      
317GND              J23   -J4  MD0200PA00X-012866Y-012937X0320Y    R180 S3      
317GND              J23   -J2  MD0200PA00X-011291Y-012937X0320Y    R180 S3      
317GND              J23   -I5  MD0200PA00X-013654Y-013449X0320Y    R180 S3      
317GND              J23   -I3  MD0200PA00X-012079Y-013449X0320Y    R180 S3      
317GND              J23   -I1  MD0200PA00X-010504Y-013449X0320Y    R180 S3      
317GND              J23   -G6  MD0200PA00X-014441Y-014591X0320Y    R180 S3      
317GND              J23   -G4  MD0200PA00X-012866Y-014591X0320Y    R180 S3      
317GND              J23   -G2  MD0200PA00X-011291Y-014591X0320Y    R180 S3      
317GND              J23   -F5  MD0200PA00X-013654Y-015102X0320Y    R180 S3      
317GND              J23   -F3  MD0200PA00X-012079Y-015102X0320Y    R180 S3      
317GND              J23   -F1  MD0200PA00X-010504Y-015102X0320Y    R180 S3      
317GND              J23   -D6  MD0200PA00X-014441Y-016244X0320Y    R180 S3      
317GND              J23   -D4  MD0200PA00X-012866Y-016244X0320Y    R180 S3      
317GND              J23   -D2  MD0200PA00X-011291Y-016244X0320Y    R180 S3      
317GND              J23   -C5  MD0200PA00X-013654Y-016756X0320Y    R180 S3      
317GND              J23   -C3  MD0200PA00X-012079Y-016756X0320Y    R180 S3      
317GND              J23   -C1  MD0200PA00X-010504Y-016756X0320Y    R180 S3      
317GND              J23   -A6  MD0200PA00X-014441Y-017898X0320Y    R180 S3      
317GND              J23   -A4  MD0200PA00X-012866Y-017898X0320Y    R180 S3      
317GND              J23   -A2  MD0200PA00X-011291Y-017898X0320Y    R180 S3      
317GND              J11   -J6  MD0200PA00X-101449Y-012937X0320Y    R180 S3      
317GND              J11   -J4  MD0200PA00X-099874Y-012937X0320Y    R180 S3      
317GND              J11   -J2  MD0200PA00X-098299Y-012937X0320Y    R180 S3      
317GND              J11   -I5  MD0200PA00X-100661Y-013449X0320Y    R180 S3      
317GND              J11   -I3  MD0200PA00X-099087Y-013449X0320Y    R180 S3      
317GND              J11   -I1  MD0200PA00X-097512Y-013449X0320Y    R180 S3      
317GND              J11   -G6  MD0200PA00X-101449Y-014591X0320Y    R180 S3      
317GND              J11   -G4  MD0200PA00X-099874Y-014591X0320Y    R180 S3      
317GND              J11   -G2  MD0200PA00X-098299Y-014591X0320Y    R180 S3      
317GND              J11   -F5  MD0200PA00X-100661Y-015102X0320Y    R180 S3      
317GND              J11   -F3  MD0200PA00X-099087Y-015102X0320Y    R180 S3      
317GND              J11   -F1  MD0200PA00X-097512Y-015102X0320Y    R180 S3      
317GND              J11   -D6  MD0200PA00X-101449Y-016244X0320Y    R180 S3      
317GND              J11   -D4  MD0200PA00X-099874Y-016244X0320Y    R180 S3      
317GND              J11   -D2  MD0200PA00X-098299Y-016244X0320Y    R180 S3      
317GND              J11   -C5  MD0200PA00X-100661Y-016756X0320Y    R180 S3      
317GND              J11   -C3  MD0200PA00X-099087Y-016756X0320Y    R180 S3      
317GND              J11   -C1  MD0200PA00X-097512Y-016756X0320Y    R180 S3      
317GND              J11   -A6  MD0200PA00X-101449Y-017898X0320Y    R180 S3      
317GND              J11   -A4  MD0200PA00X-099874Y-017898X0320Y    R180 S3      
317GND              J11   -A2  MD0200PA00X-098299Y-017898X0320Y    R180 S3      
317GND              J19   -J6  MD0200PA00X-032693Y-012937X0320Y    R180 S3      
317GND              J19   -J4  MD0200PA00X-031118Y-012937X0320Y    R180 S3      
317GND              J19   -J2  MD0200PA00X-029543Y-012937X0320Y    R180 S3      
317GND              J19   -I1  MD0200PA00X-028756Y-013449X0320Y    R180 S3      
317GND              J19   -G6  MD0200PA00X-032693Y-014591X0320Y    R180 S3      
317GND              J19   -G2  MD0200PA00X-029543Y-014591X0320Y    R180 S3      
317GND              J19   -F5  MD0200PA00X-031906Y-015102X0320Y    R180 S3      
317GND              J19   -F1  MD0200PA00X-028756Y-015102X0320Y    R180 S3      
317GND              J19   -D6  MD0200PA00X-032693Y-016244X0320Y    R180 S3      
317GND              J19   -D4  MD0200PA00X-031118Y-016244X0320Y    R180 S3      
317GND              J19   -D2  MD0200PA00X-029543Y-016244X0320Y    R180 S3      
317GND              J19   -C5  MD0200PA00X-031906Y-016756X0320Y    R180 S3      
317GND              J19   -C3  MD0200PA00X-030331Y-016756X0320Y    R180 S3      
317GND              J19   -C1  MD0200PA00X-028756Y-016756X0320Y    R180 S3      
317GND              J19   -A6  MD0200PA00X-032693Y-017898X0320Y    R180 S3      
317GND              J19   -A4  MD0200PA00X-031118Y-017898X0320Y    R180 S3      
317GND              J19   -A2  MD0200PA00X-029543Y-017898X0320Y    R180 S3      
317GND              J7    -J6  MD0200PA00X-119701Y-012937X0320Y    R180 S3      
317GND              J7    -J4  MD0200PA00X-118126Y-012937X0320Y    R180 S3      
317GND              J7    -J2  MD0200PA00X-116551Y-012937X0320Y    R180 S3      
317GND              J7    -I1  MD0200PA00X-115764Y-013449X0320Y    R180 S3      
317GND              J7    -G6  MD0200PA00X-119701Y-014591X0320Y    R180 S3      
317GND              J7    -G2  MD0200PA00X-116551Y-014591X0320Y    R180 S3      
317GND              J7    -F5  MD0200PA00X-118913Y-015102X0320Y    R180 S3      
317GND              J7    -F1  MD0200PA00X-115764Y-015102X0320Y    R180 S3      
317GND              J7    -D6  MD0200PA00X-119701Y-016244X0320Y    R180 S3      
317GND              J7    -D4  MD0200PA00X-118126Y-016244X0320Y    R180 S3      
317GND              J7    -D2  MD0200PA00X-116551Y-016244X0320Y    R180 S3      
317GND              J7    -C5  MD0200PA00X-118913Y-016756X0320Y    R180 S3      
317GND              J7    -C3  MD0200PA00X-117339Y-016756X0320Y    R180 S3      
317GND              J7    -C1  MD0200PA00X-115764Y-016756X0320Y    R180 S3      
317GND              J7    -A6  MD0200PA00X-119701Y-017898X0320Y    R180 S3      
317GND              J7    -A4  MD0200PA00X-118126Y-017898X0320Y    R180 S3      
317GND              J7    -A2  MD0200PA00X-116551Y-017898X0320Y    R180 S3      
317GND              J4    -4F  MD0300PA00X-131988Y-017504X0540Y         S3      
317GND              J4    -4E  MD0300PA00X-132776Y-017504X0540Y         S3      
317GND              J4    -4D  MD0300PA00X-131988Y-016717X0540Y         S3      
317GND              J4    -4C  MD0300PA00X-132776Y-016717X0540Y         S3      
317GND              J4    -4B  MD0300PA00X-131988Y-015929X0540Y         S3      
317GND              J4    -4A  MD0300PA00X-132776Y-015929X0540Y         S3      
317GND              J4    -1F  MD0300PA00X-131988Y-014354X0540Y         S3      
317GND              J4    -1E  MD0300PA00X-132776Y-014354X0540Y         S3      
317GND              J4    -1D  MD0300PA00X-131988Y-013567X0540Y         S3      
317GND              J4    -1C  MD0300PA00X-132776Y-013567X0540Y         S3      
317GND              J4    -1B  MD0300PA00X-131988Y-012780X0540Y         S3      
317GND              J4    -1A  MD0300PA00X-132776Y-012780X0540Y0540     S3      
317GND              J16   -4F  MD0300PA00X-044980Y-017504X0540Y         S3      
317GND              J16   -4E  MD0300PA00X-045768Y-017504X0540Y         S3      
317GND              J16   -4D  MD0300PA00X-044980Y-016717X0540Y         S3      
317GND              J16   -4C  MD0300PA00X-045768Y-016717X0540Y         S3      
317GND              J16   -4B  MD0300PA00X-044980Y-015929X0540Y         S3      
317GND              J16   -4A  MD0300PA00X-045768Y-015929X0540Y         S3      
317GND              J16   -1F  MD0300PA00X-044980Y-014354X0540Y         S3      
317GND              J16   -1E  MD0300PA00X-045768Y-014354X0540Y         S3      
317GND              J16   -1D  MD0300PA00X-044980Y-013567X0540Y         S3      
317GND              J16   -1C  MD0300PA00X-045768Y-013567X0540Y         S3      
317GND              J16   -1B  MD0300PA00X-044980Y-012780X0540Y         S3      
317GND              J16   -1A  MD0300PA00X-045768Y-012780X0540Y0540     S3      
317GND              J1    -P10 MD0200PA00X-161598Y-009591X0320Y    R180 S3      
317GND              J1    -P8  MD0200PA00X-160024Y-009591X0320Y    R180 S3      
317GND              J1    -P6  MD0200PA00X-158449Y-009591X0320Y    R180 S3      
317GND              J1    -P4  MD0200PA00X-156874Y-009591X0320Y    R180 S3      
317GND              J1    -P2  MD0200PA00X-155299Y-009591X0320Y    R180 S3      
317GND              J1    -M10 MD0200PA00X-161598Y-011244X0320Y    R180 S3      
317GND              J1    -J8  MD0200PA00X-160024Y-012898X0320Y    R180 S3      
317GND              J1    -L9  MD0200PA00X-160811Y-011756X0320Y    R180 S3      
317GND              J1    -M8  MD0200PA00X-160024Y-011244X0320Y    R180 S3      
317GND              J1    -M9  MD0200PA00X-160811Y-011205X0320Y    R180 S3      
317GND              J1    -N9  MD0200PA00X-160811Y-010654X0320Y    R180 S3      
317GND              J1    -O9  MD0200PA00X-160811Y-010102X0320Y    R180 S3      
317GND              J1    -L7  MD0200PA00X-159236Y-011756X0320Y    R180 S3      
317GND              J1    -O7  MD0200PA00X-159236Y-010102X0320Y    R180 S3      
317GND              J1    -J6  MD0200PA00X-158449Y-012898X0320Y    R180 S3      
317GND              J1    -L5  MD0200PA00X-157661Y-011756X0320Y    R180 S3      
317GND              J1    -O5  MD0200PA00X-157661Y-010102X0320Y    R180 S3      
317GND              J1    -M6  MD0200PA00X-158449Y-011244X0320Y    R180 S3      
317GND              J1    -J4  MD0200PA00X-156874Y-012898X0320Y    R180 S3      
317GND              J1    -M4  MD0200PA00X-156874Y-011244X0320Y    R180 S3      
317GND              J1    -J2  MD0200PA00X-155299Y-012898X0320Y    R180 S3      
317GND              J1    -L3  MD0200PA00X-156087Y-011756X0320Y    R180 S3      
317GND              J1    -O3  MD0200PA00X-156087Y-010102X0320Y    R180 S3      
317GND              J1    -M2  MD0200PA00X-155299Y-011244X0320Y    R180 S3      
317GND              J1    -L1  MD0200PA00X-154512Y-011756X0320Y    R180 S3      
317GND              J1    -O1  MD0200PA00X-154512Y-010102X0320Y    R180 S3      
317GND              J1    -A10 MD0200PA00X-161598Y-017858X0320Y    R180 S3      
317GND              J1    -D10 MD0200PA00X-161598Y-016205X0320Y    R180 S3      
317GND              J1    -F10 MD0200PA00X-161598Y-015102X0320Y    R180 S3      
317GND              J1    -H10 MD0200PA00X-161598Y-014000X0320Y    R180 S3      
317GND              J1    -G10 MD0200PA00X-161598Y-014551X0320Y    R180 S3      
317GND              J1    -C9  MD0200PA00X-160811Y-016717X0320Y    R180 S3      
317GND              J1    -F9  MD0200PA00X-160811Y-015063X0320Y    R180 S3      
317GND              J1    -I9  MD0200PA00X-160811Y-013409X0320Y    R180 S3      
317GND              J1    -I7  MD0200PA00X-159236Y-013409X0320Y    R180 S3      
317GND              J1    -I5  MD0200PA00X-157661Y-013409X0320Y    R180 S3      
317GND              J1    -I3  MD0200PA00X-156087Y-013409X0320Y    R180 S3      
317GND              J1    -I1  MD0200PA00X-154512Y-013409X0320Y    R180 S3      
317GND              J1    -G8  MD0200PA00X-160024Y-014551X0320Y    R180 S3      
317GND              J1    -G6  MD0200PA00X-158449Y-014551X0320Y    R180 S3      
317GND              J1    -G4  MD0200PA00X-156874Y-014551X0320Y    R180 S3      
317GND              J1    -G2  MD0200PA00X-155299Y-014551X0320Y    R180 S3      
317GND              J1    -F7  MD0200PA00X-159236Y-015063X0320Y    R180 S3      
317GND              J1    -F5  MD0200PA00X-157661Y-015063X0320Y    R180 S3      
317GND              J1    -F3  MD0200PA00X-156087Y-015063X0320Y    R180 S3      
317GND              J1    -F1  MD0200PA00X-154512Y-015063X0320Y    R180 S3      
317GND              J1    -D8  MD0200PA00X-160024Y-016205X0320Y    R180 S3      
317GND              J1    -D6  MD0200PA00X-158449Y-016205X0320Y    R180 S3      
317GND              J1    -D4  MD0200PA00X-156874Y-016205X0320Y    R180 S3      
317GND              J1    -D2  MD0200PA00X-155299Y-016205X0320Y    R180 S3      
317GND              J1    -C7  MD0200PA00X-159236Y-016717X0320Y    R180 S3      
317GND              J1    -C5  MD0200PA00X-157661Y-016717X0320Y    R180 S3      
317GND              J1    -C3  MD0200PA00X-156087Y-016717X0320Y    R180 S3      
317GND              J1    -C1  MD0200PA00X-154512Y-016717X0320Y    R180 S3      
317GND              J1    -A8  MD0200PA00X-160024Y-017858X0320Y    R180 S3      
317GND              J1    -A6  MD0200PA00X-158449Y-017858X0320Y    R180 S3      
317GND              J1    -A4  MD0200PA00X-156874Y-017858X0320Y    R180 S3      
317GND              J1    -A2  MD0200PA00X-155299Y-017858X0320Y    R180 S3      
317GND              J13   -A10 MD0200PA00X-074591Y-017858X0320Y    R180 S3      
317GND              J13   -D10 MD0200PA00X-074591Y-016205X0320Y    R180 S3      
317GND              J13   -F10 MD0200PA00X-074591Y-015102X0320Y    R180 S3      
317GND              J13   -H10 MD0200PA00X-074591Y-014000X0320Y    R180 S3      
317GND              J13   -G10 MD0200PA00X-074591Y-014551X0320Y    R180 S3      
317GND              J13   -C9  MD0200PA00X-073803Y-016717X0320Y    R180 S3      
317GND              J13   -F9  MD0200PA00X-073803Y-015063X0320Y    R180 S3      
317GND              J13   -G8  MD0200PA00X-073016Y-014551X0320Y    R180 S3      
317GND              J13   -G6  MD0200PA00X-071441Y-014551X0320Y    R180 S3      
317GND              J13   -G4  MD0200PA00X-069866Y-014551X0320Y    R180 S3      
317GND              J13   -G2  MD0200PA00X-068291Y-014551X0320Y    R180 S3      
317GND              J13   -F7  MD0200PA00X-072228Y-015063X0320Y    R180 S3      
317GND              J13   -F5  MD0200PA00X-070654Y-015063X0320Y    R180 S3      
317GND              J13   -F3  MD0200PA00X-069079Y-015063X0320Y    R180 S3      
317GND              J13   -F1  MD0200PA00X-067504Y-015063X0320Y    R180 S3      
317GND              J13   -D8  MD0200PA00X-073016Y-016205X0320Y    R180 S3      
317GND              J13   -D6  MD0200PA00X-071441Y-016205X0320Y    R180 S3      
317GND              J13   -D4  MD0200PA00X-069866Y-016205X0320Y    R180 S3      
317GND              J13   -D2  MD0200PA00X-068291Y-016205X0320Y    R180 S3      
317GND              J13   -C7  MD0200PA00X-072228Y-016717X0320Y    R180 S3      
317GND              J13   -C5  MD0200PA00X-070654Y-016717X0320Y    R180 S3      
317GND              J13   -C3  MD0200PA00X-069079Y-016717X0320Y    R180 S3      
317GND              J13   -C1  MD0200PA00X-067504Y-016717X0320Y    R180 S3      
317GND              J13   -A8  MD0200PA00X-073016Y-017858X0320Y    R180 S3      
317GND              J13   -A6  MD0200PA00X-071441Y-017858X0320Y    R180 S3      
317GND              J13   -A4  MD0200PA00X-069866Y-017858X0320Y    R180 S3      
317GND              J13   -A2  MD0200PA00X-068291Y-017858X0320Y    R180 S3      
317GND              J9    -12  MD0410PA00X-128248Y-002386X0610Y    R270 S3      
317GND              J9    -11  MD0410PA00X-128248Y-005929X0610Y    R270 S3      
317GND              J9    -10  MD0410PA00X-128248Y-009472X0610Y    R270 S3      
317GND              J9    -5   MD0410PA00X-120768Y-000614X0610Y    R270 S3      
317GND              J9    -4   MD0410PA00X-120768Y-004157X0610Y    R270 S3      
317GND              J9    -3   MD0410PA00X-120768Y-007701X0610Y    R270 S3      
317GND              J9    -2   MD0410PA00X-120768Y-011244X0610Y    R270 S3      
317GND              J21   -12  MD0410PA00X-041240Y-002386X0610Y    R270 S3      
317GND              J21   -11  MD0410PA00X-041240Y-005929X0610Y    R270 S3      
317GND              J21   -10  MD0410PA00X-041240Y-009472X0610Y    R270 S3      
317GND              J21   -5   MD0410PA00X-033760Y-000614X0610Y    R270 S3      
317GND              J21   -3   MD0410PA00X-033760Y-007701X0610Y    R270 S3      
317GND              J21   -2   MD0410PA00X-033760Y-011244X0610Y    R270 S3      
327GND              J2    -128        A01X-145919Y-009439X0250Y    R090 S1      
327GND              J2    -120        A01X-145919Y-009939X0250Y    R090 S1      
327GND              J2    -96         A01X-145919Y-011439X0250Y    R090 S1      
327GND              J2    -88         A01X-145919Y-011939X0250Y    R090 S1      
327GND              J2    -64         A01X-145919Y-013439X0250Y    R090 S1      
327GND              J2    -56         A01X-145919Y-013939X0250Y    R090 S1      
327GND              J2    -32         A01X-145919Y-015439X0250Y    R090 S1      
327GND              J2    -24         A01X-145919Y-015939X0250Y    R090 S1      
327GND              J2    -135        A01X-146419Y-008939X0250Y    R090 S1      
327GND              J2    -111        A01X-146419Y-010439X0250Y    R090 S1      
327GND              J2    -103        A01X-146419Y-010939X0250Y    R090 S1      
327GND              J2    -79         A01X-146419Y-012439X0250Y    R090 S1      
327GND              J2    -71         A01X-146419Y-012939X0250Y    R090 S1      
327GND              J2    -47         A01X-146419Y-014439X0250Y    R090 S1      
327GND              J2    -39         A01X-146419Y-014939X0250Y    R090 S1      
327GND              J2    -15         A01X-146419Y-016439X0250Y    R090 S1      
327GND              J2    -7          A01X-146419Y-016939X0250Y    R090 S1      
327GND              J2    -126        A01X-146919Y-009439X0250Y    R090 S1      
327GND              J2    -118        A01X-146919Y-009939X0250Y    R090 S1      
327GND              J2    -94         A01X-146919Y-011439X0250Y    R090 S1      
327GND              J2    -86         A01X-146919Y-011939X0250Y    R090 S1      
327GND              J2    -62         A01X-146919Y-013439X0250Y    R090 S1      
327GND              J2    -54         A01X-146919Y-013939X0250Y    R090 S1      
327GND              J2    -30         A01X-146919Y-015439X0250Y    R090 S1      
327GND              J2    -22         A01X-146919Y-015939X0250Y    R090 S1      
327GND              J2    -141        A01X-147419Y-008439X0250Y    R090 S1      
327GND              J2    -133        A01X-147419Y-008939X0250Y    R090 S1      
327GND              J2    -109        A01X-147419Y-010439X0250Y    R090 S1      
327GND              J2    -101        A01X-147419Y-010939X0250Y    R090 S1      
327GND              J2    -77         A01X-147419Y-012439X0250Y    R090 S1      
327GND              J2    -69         A01X-147419Y-012939X0250Y    R090 S1      
327GND              J2    -45         A01X-147419Y-014439X0250Y    R090 S1      
327GND              J2    -37         A01X-147419Y-014939X0250Y    R090 S1      
327GND              J2    -13         A01X-147419Y-016439X0250Y    R090 S1      
327GND              J2    -5          A01X-147419Y-016939X0250Y    R090 S1      
327GND              J2    -124        A01X-147919Y-009439X0250Y    R090 S1      
327GND              J2    -116        A01X-147919Y-009939X0250Y    R090 S1      
327GND              J2    -92         A01X-147919Y-011439X0250Y    R090 S1      
327GND              J2    -84         A01X-147919Y-011939X0250Y    R090 S1      
327GND              J2    -60         A01X-147919Y-013439X0250Y    R090 S1      
327GND              J2    -52         A01X-147919Y-013939X0250Y    R090 S1      
327GND              J2    -28         A01X-147919Y-015439X0250Y    R090 S1      
327GND              J2    -20         A01X-147919Y-015939X0250Y    R090 S1      
327GND              J2    -139        A01X-148419Y-008439X0250Y    R090 S1      
327GND              J2    -131        A01X-148419Y-008939X0250Y    R090 S1      
327GND              J2    -107        A01X-148419Y-010439X0250Y    R090 S1      
327GND              J2    -99         A01X-148419Y-010939X0250Y    R090 S1      
327GND              J2    -75         A01X-148419Y-012439X0250Y    R090 S1      
327GND              J2    -67         A01X-148419Y-012939X0250Y    R090 S1      
327GND              J2    -43         A01X-148419Y-014439X0250Y    R090 S1      
327GND              J2    -35         A01X-148419Y-014939X0250Y    R090 S1      
327GND              J2    -11         A01X-148419Y-016439X0250Y    R090 S1      
327GND              J2    -3          A01X-148419Y-016939X0250Y    R090 S1      
327GND              J2    -146        A01X-148919Y-007939X0250Y    R090 S1      
327GND              J2    -122        A01X-148919Y-009439X0250Y    R090 S1      
327GND              J2    -114        A01X-148919Y-009939X0250Y    R090 S1      
327GND              J2    -90         A01X-148919Y-011439X0250Y    R090 S1      
327GND              J2    -82         A01X-148919Y-011939X0250Y    R090 S1      
327GND              J2    -58         A01X-148919Y-013439X0250Y    R090 S1      
327GND              J2    -50         A01X-148919Y-013939X0250Y    R090 S1      
327GND              J2    -26         A01X-148919Y-015439X0250Y    R090 S1      
327GND              J2    -18         A01X-148919Y-015939X0250Y    R090 S1      
327GND              J2    -129        A01X-149419Y-008939X0250Y    R090 S1      
327GND              J2    -105        A01X-149419Y-010439X0250Y    R090 S1      
327GND              J2    -97         A01X-149419Y-010939X0250Y    R090 S1      
327GND              J2    -73         A01X-149419Y-012439X0250Y    R090 S1      
327GND              J2    -65         A01X-149419Y-012939X0250Y    R090 S1      
327GND              J2    -41         A01X-149419Y-014439X0250Y    R090 S1      
327GND              J2    -33         A01X-149419Y-014939X0250Y    R090 S1      
327GND              J2    -9          A01X-149419Y-016439X0250Y    R090 S1      
327GND              J2    -1          A01X-149419Y-016939X0250Y    R090 S1      
317GND              J24   -10  MD0240PA00X-015492Y+000146X0440Y    R180 S3      
317GND              J24   -4   MD0240PA00X-014508Y-010531X0440Y    R180 S3      
317GND              J24   -2D9 MD0150PA00X-014508Y-009582X0270Y    R180 S3      
317GND              J24   -2C9 MD0150PA00X-014508Y-008086X0270Y    R180 S3      
317GND              J24   -2B9 MD0150PA00X-014508Y-006590X0270Y    R180 S3      
317GND              J24   -2A9 MD0150PA00X-014508Y-005094X0270Y    R180 S3      
317GND              J24   -2D6 MD0150PA00X-013622Y-009582X0270Y    R180 S3      
317GND              J24   -2C6 MD0150PA00X-013622Y-008086X0270Y    R180 S3      
317GND              J24   -2B6 MD0150PA00X-013622Y-006590X0270Y    R180 S3      
317GND              J24   -2A6 MD0150PA00X-013622Y-005094X0270Y    R180 S3      
317GND              J24   -3   MD0240PA00X-012736Y-010531X0440Y    R180 S3      
317GND              J24   -2D3 MD0150PA00X-012736Y-009582X0270Y    R180 S3      
317GND              J24   -2C3 MD0150PA00X-012736Y-008086X0270Y    R180 S3      
317GND              J24   -2B3 MD0150PA00X-012736Y-006590X0270Y    R180 S3      
317GND              J24   -2A3 MD0150PA00X-012736Y-005094X0270Y    R180 S3      
317GND              J24   -9   MD0240PA00X-011161Y+000146X0440Y    R180 S3      
317GND              J24   -8   MD0240PA00X-006831Y+000146X0440Y    R180 S3      
317GND              J24   -6   MD0240PA00X-011161Y-005094X0440Y    R180 S3      
317GND              J24   -5   MD0240PA00X-006831Y-005094X0440Y    R180 S3      
317GND              J24   -2   MD0240PA00X-010177Y-010531X0440Y    R180 S3      
317GND              J24   -1   MD0240PA00X-008406Y-010531X0440Y    R180 S3      
317GND              J24   -1A9 MD0150PA00X-010177Y-005094X0270Y    R180 S3      
317GND              J24   -1A6 MD0150PA00X-009291Y-005094X0270Y    R180 S3      
317GND              J24   -1A3 MD0150PA00X-008406Y-005094X0270Y    R180 S3      
317GND              J24   -1B9 MD0150PA00X-010177Y-006590X0270Y    R180 S3      
317GND              J24   -1B6 MD0150PA00X-009291Y-006590X0270Y    R180 S3      
317GND              J24   -1B3 MD0150PA00X-008406Y-006590X0270Y    R180 S3      
317GND              J24   -1C9 MD0150PA00X-010177Y-008086X0270Y    R180 S3      
317GND              J24   -1C6 MD0150PA00X-009291Y-008086X0270Y    R180 S3      
317GND              J24   -1C3 MD0150PA00X-008406Y-008086X0270Y    R180 S3      
317GND              J24   -1D9 MD0150PA00X-010177Y-009582X0270Y    R180 S3      
317GND              J24   -1D6 MD0150PA00X-009291Y-009582X0270Y    R180 S3      
317GND              J24   -1D3 MD0150PA00X-008406Y-009582X0270Y    R180 S3      
317GND              J12   -10  MD0240PA00X-102500Y+000146X0440Y    R180 S3      
317GND              J12   -4   MD0240PA00X-101516Y-010531X0440Y    R180 S3      
317GND              J12   -2D9 MD0150PA00X-101516Y-009582X0270Y    R180 S3      
317GND              J12   -2C9 MD0150PA00X-101516Y-008086X0270Y    R180 S3      
317GND              J12   -2B9 MD0150PA00X-101516Y-006590X0270Y    R180 S3      
317GND              J12   -2A9 MD0150PA00X-101516Y-005094X0270Y    R180 S3      
317GND              J12   -2D6 MD0150PA00X-100630Y-009582X0270Y    R180 S3      
317GND              J12   -2C6 MD0150PA00X-100630Y-008086X0270Y    R180 S3      
317GND              J12   -2B6 MD0150PA00X-100630Y-006590X0270Y    R180 S3      
317GND              J12   -2A6 MD0150PA00X-100630Y-005094X0270Y    R180 S3      
317GND              J12   -3   MD0240PA00X-099744Y-010531X0440Y    R180 S3      
317GND              J12   -2D3 MD0150PA00X-099744Y-009582X0270Y    R180 S3      
317GND              J12   -2C3 MD0150PA00X-099744Y-008086X0270Y    R180 S3      
317GND              J12   -2B3 MD0150PA00X-099744Y-006590X0270Y    R180 S3      
317GND              J12   -2A3 MD0150PA00X-099744Y-005094X0270Y    R180 S3      
317GND              J12   -9   MD0240PA00X-098169Y+000146X0440Y    R180 S3      
317GND              J12   -8   MD0240PA00X-093839Y+000146X0440Y    R180 S3      
317GND              J12   -6   MD0240PA00X-098169Y-005094X0440Y    R180 S3      
317GND              J12   -5   MD0240PA00X-093839Y-005094X0440Y    R180 S3      
317GND              J12   -2   MD0240PA00X-097185Y-010531X0440Y    R180 S3      
317GND              J12   -1   MD0240PA00X-095413Y-010531X0440Y    R180 S3      
317GND              J12   -1A9 MD0150PA00X-097185Y-005094X0270Y    R180 S3      
317GND              J12   -1A6 MD0150PA00X-096299Y-005094X0270Y    R180 S3      
317GND              J12   -1A3 MD0150PA00X-095413Y-005094X0270Y    R180 S3      
317GND              J12   -1B9 MD0150PA00X-097185Y-006590X0270Y    R180 S3      
317GND              J12   -1B6 MD0150PA00X-096299Y-006590X0270Y    R180 S3      
317GND              J12   -1B3 MD0150PA00X-095413Y-006590X0270Y    R180 S3      
317GND              J12   -1C9 MD0150PA00X-097185Y-008086X0270Y    R180 S3      
317GND              J12   -1C6 MD0150PA00X-096299Y-008086X0270Y    R180 S3      
317GND              J12   -1C3 MD0150PA00X-095413Y-008086X0270Y    R180 S3      
317GND              J12   -1D9 MD0150PA00X-097185Y-009582X0270Y    R180 S3      
317GND              J12   -1D6 MD0150PA00X-096299Y-009582X0270Y    R180 S3      
317GND              J12   -1D3 MD0150PA00X-095413Y-009582X0270Y    R180 S3      
317GND              J6    -1   MD0380PA00X-111319Y-015063X0580Y    R180 S3      
317GND              J6    -14  MD0410PA00X-110750Y-008331X0790Y0790R180 S3      
317GND              J6    -2   MD0380PA00X-109429Y-015063X0580Y    R180 S3      
317GND              J6    -3   MD0380PA00X-113209Y-015063X0580Y    R180 S3      
317GND              J6    -12  MD0380PA00X-114124Y-009433X0580Y    R180 S3      
317GND              J6    -9   MD0380PA00X-114124Y-011283X0580Y    R180 S3      
317GND              J6    -6   MD0380PA00X-114124Y-013252X0580Y    R180 S3      
317GND              J6    -5   MD0380PA00X-108514Y-013252X0580Y    R180 S3      
317GND              J6    -8   MD0380PA00X-108514Y-011283X0580Y    R180 S3      
317GND              J6    -11  MD0380PA00X-108514Y-009433X0580Y    R180 S3      
317GND              J6    -15  MD0410PA00X-112876Y-008331X0790Y0790R180 S3      
317GND              J6    -20  MD0410PA00X-111892Y-000457X0790Y0790R180 S3      
317GND              J6    -4   MD0410PA00X-114124Y-014236X0790Y0790R180 S3      
317GND              J6    -10  MD0410PA00X-114124Y-010299X0790Y0790R180 S3      
317GND              J6    -16  MD0410PA00X-114124Y-006362X0790Y0790R180 S3      
317GND              J6    -18  MD0410PA00X-114124Y-002425X0790Y0790R180 S3      
317GND              J6    -7   MD0330PA00X-108514Y-012268X0790Y0790R180 S3      
317GND              J6    -19  MD0410PA00X-108514Y-000457X0790Y0790R180 S3      
317GND              J6    -17  MD0410PA00X-108514Y-004394X0790Y0790R180 S3      
317GND              J6    -13  MD0410PA00X-108514Y-008331X0790Y0790R180 S3      
317GND              J18   -1   MD0380PA00X-024311Y-015063X0580Y    R180 S3      
317GND              J18   -14  MD0410PA00X-023742Y-008331X0790Y0790R180 S3      
317GND              J18   -2   MD0380PA00X-022421Y-015063X0580Y    R180 S3      
317GND              J18   -3   MD0380PA00X-026201Y-015063X0580Y    R180 S3      
317GND              J18   -12  MD0380PA00X-027116Y-009433X0580Y    R180 S3      
317GND              J18   -9   MD0380PA00X-027116Y-011283X0580Y    R180 S3      
317GND              J18   -6   MD0380PA00X-027116Y-013252X0580Y    R180 S3      
317GND              J18   -5   MD0380PA00X-021506Y-013252X0580Y    R180 S3      
317GND              J18   -8   MD0380PA00X-021506Y-011283X0580Y    R180 S3      
317GND              J18   -11  MD0380PA00X-021506Y-009433X0580Y    R180 S3      
317GND              J18   -15  MD0410PA00X-025868Y-008331X0790Y0790R180 S3      
317GND              J18   -20  MD0410PA00X-024884Y-000457X0790Y0790R180 S3      
317GND              J18   -4   MD0410PA00X-027116Y-014236X0790Y0790R180 S3      
317GND              J18   -10  MD0410PA00X-027116Y-010299X0790Y0790R180 S3      
317GND              J18   -16  MD0410PA00X-027116Y-006362X0790Y0790R180 S3      
317GND              J18   -18  MD0410PA00X-027116Y-002425X0790Y0790R180 S3      
317GND              J18   -7   MD0330PA00X-021506Y-012268X0790Y0790R180 S3      
317GND              J18   -19  MD0410PA00X-021506Y-000457X0790Y0790R180 S3      
317GND              J18   -17  MD0410PA00X-021506Y-004394X0790Y0790R180 S3      
317GND              J18   -13  MD0410PA00X-021506Y-008331X0790Y0790R180 S3      
327GND              C4    -2          A01X-132223Y-008205X0200Y0230R180 S1      
317GND              VIA   -    MD0100PA00X-061661Y-016689X0220Y         S0      
317GND              VIA   -    MD0100PA00X-061661Y-016189X0220Y         S0      
317GND              VIA   -    MD0100PA00X-061661Y-014189X0220Y         S0      
317GND              VIA   -    MD0100PA00X-061661Y-014689X0220Y         S0      
317GND              VIA   -    MD0100PA00X-061661Y-012189X0220Y         S0      
317GND              VIA   -    MD0100PA00X-061661Y-012689X0220Y         S0      
317GND              VIA   -    MD0100PA00X-061661Y-010189X0220Y         S0      
317GND              VIA   -    MD0100PA00X-061661Y-010689X0220Y         S0      
317GND              VIA   -    MD0100PA00X-061661Y-008689X0220Y         S0      
317GND              VIA   -    MD0100PA00X-061661Y-008189X0220Y         S0      
317GND              VIA   -    MD0100PA00X-059661Y-016689X0220Y         S0      
317GND              VIA   -    MD0100PA00X-060661Y-016689X0220Y         S0      
317GND              VIA   -    MD0100PA00X-060661Y-016189X0220Y         S0      
317GND              VIA   -    MD0100PA00X-061161Y-015689X0220Y         S0      
317GND              VIA   -    MD0100PA00X-061161Y-015189X0220Y         S0      
317GND              VIA   -    MD0100PA00X-060161Y-015189X0220Y         S0      
317GND              VIA   -    MD0100PA00X-060161Y-015689X0220Y         S0      
317GND              VIA   -    MD0100PA00X-059661Y-016189X0220Y         S0      
317GND              VIA   -    MD0100PA00X-061161Y-013689X0220Y         S0      
317GND              VIA   -    MD0100PA00X-060161Y-013689X0220Y         S0      
317GND              VIA   -    MD0100PA00X-059661Y-014189X0220Y         S0      
317GND              VIA   -    MD0100PA00X-060661Y-014189X0220Y         S0      
317GND              VIA   -    MD0100PA00X-059661Y-014689X0220Y         S0      
317GND              VIA   -    MD0100PA00X-060661Y-014689X0220Y         S0      
317GND              VIA   -    MD0100PA00X-061161Y-013189X0220Y         S0      
317GND              VIA   -    MD0100PA00X-059661Y-012189X0220Y         S0      
317GND              VIA   -    MD0100PA00X-060661Y-012189X0220Y         S0      
317GND              VIA   -    MD0100PA00X-059661Y-012689X0220Y         S0      
317GND              VIA   -    MD0100PA00X-060661Y-012689X0220Y         S0      
317GND              VIA   -    MD0100PA00X-060161Y-013189X0220Y         S0      
317GND              VIA   -    MD0100PA00X-061161Y-011189X0220Y         S0      
317GND              VIA   -    MD0100PA00X-061161Y-011689X0220Y         S0      
317GND              VIA   -    MD0100PA00X-059661Y-010189X0220Y         S0      
317GND              VIA   -    MD0100PA00X-060661Y-010189X0220Y         S0      
317GND              VIA   -    MD0100PA00X-059661Y-010689X0220Y         S0      
317GND              VIA   -    MD0100PA00X-060661Y-010689X0220Y         S0      
317GND              VIA   -    MD0100PA00X-060161Y-011189X0220Y         S0      
317GND              VIA   -    MD0100PA00X-060161Y-011689X0220Y         S0      
317GND              VIA   -    MD0100PA00X-061161Y-009189X0220Y         S0      
317GND              VIA   -    MD0100PA00X-061161Y-009689X0220Y         S0      
317GND              VIA   -    MD0100PA00X-059661Y-008689X0220Y         S0      
317GND              VIA   -    MD0100PA00X-060661Y-008689X0220Y         S0      
317GND              VIA   -    MD0100PA00X-060161Y-009189X0220Y         S0      
317GND              VIA   -    MD0100PA00X-060161Y-009689X0220Y         S0      
317GND              VIA   -    MD0100PA00X-060661Y-008189X0220Y         S0      
317GND              VIA   -    MD0100PA00X-059161Y-015189X0220Y         S0      
317GND              VIA   -    MD0100PA00X-059161Y-015689X0220Y         S0      
317GND              VIA   -    MD0100PA00X-059161Y-013689X0220Y         S0      
317GND              VIA   -    MD0100PA00X-059161Y-013189X0220Y         S0      
317GND              VIA   -    MD0100PA00X-059161Y-011189X0220Y         S0      
317GND              VIA   -    MD0100PA00X-059161Y-011689X0220Y         S0      
317GND              VIA   -    MD0100PA00X-059161Y-009189X0220Y         S0      
317GND              VIA   -    MD0100PA00X-059161Y-009689X0220Y         S0      
317GND              VIA   -    MD0100PA00X-062157Y-015185X0220Y         S0      
317GND              VIA   -    MD0100PA00X-062161Y-015689X0220Y         S0      
317GND              VIA   -    MD0100PA00X-062696Y-016439X0220Y         S0      
317GND              VIA   -    M      A01X-062696Y-016939X0220Y         S2      
017GND              VIA   -    M      A08X-062696Y-016939X0320Y         S2      
017GND                    -    MD0100PA00X-062696Y-016939                       
317GND              VIA   -    MD0100PA00X-062696Y-010939X0220Y         S0      
317GND              VIA   -    MD0100PA00X-062696Y-010439X0220Y         S0      
317GND              VIA   -    MD0100PA00X-062696Y-008939X0220Y         S0      
317GND              VIA   -    MD0100PA00X-062161Y-009189X0220Y         S0      
317GND              VIA   -    MD0100PA00X-062161Y-009689X0220Y         S0      
317GND              VIA   -    MD0100PA00X-062161Y-011189X0220Y         S0      
317GND              VIA   -    MD0100PA00X-062161Y-011689X0220Y         S0      
317GND              VIA   -    MD0100PA00X-062161Y-013689X0220Y         S0      
317GND              VIA   -    MD0100PA00X-062161Y-013189X0220Y         S0      
327GND              J14   -3          A01X-061411Y-016939X0250Y    R090 S1      
327GND              J14   -35         A01X-061411Y-014939X0250Y    R090 S1      
327GND              J14   -11         A01X-061411Y-016439X0250Y    R090 S1      
327GND              J14   -43         A01X-061411Y-014439X0250Y    R090 S1      
327GND              J14   -75         A01X-061411Y-012439X0250Y    R090 S1      
327GND              J14   -67         A01X-061411Y-012939X0250Y    R090 S1      
327GND              J14   -107        A01X-061411Y-010439X0250Y    R090 S1      
327GND              J14   -99         A01X-061411Y-010939X0250Y    R090 S1      
327GND              J14   -131        A01X-061411Y-008939X0250Y    R090 S1      
327GND              J14   -139        A01X-061411Y-008439X0250Y    R090 S1      
327GND              J14   -7          A01X-059411Y-016939X0250Y    R090 S1      
327GND              J14   -5          A01X-060411Y-016939X0250Y    R090 S1      
327GND              J14   -37         A01X-060411Y-014939X0250Y    R090 S1      
327GND              J14   -13         A01X-060411Y-016439X0250Y    R090 S1      
327GND              J14   -20         A01X-060911Y-015939X0250Y    R090 S1      
327GND              J14   -28         A01X-060911Y-015439X0250Y    R090 S1      
327GND              J14   -30         A01X-059911Y-015439X0250Y    R090 S1      
327GND              J14   -22         A01X-059911Y-015939X0250Y    R090 S1      
327GND              J14   -15         A01X-059411Y-016439X0250Y    R090 S1      
327GND              J14   -60         A01X-060911Y-013439X0250Y    R090 S1      
327GND              J14   -62         A01X-059911Y-013439X0250Y    R090 S1      
327GND              J14   -52         A01X-060911Y-013939X0250Y    R090 S1      
327GND              J14   -54         A01X-059911Y-013939X0250Y    R090 S1      
327GND              J14   -47         A01X-059411Y-014439X0250Y    R090 S1      
327GND              J14   -45         A01X-060411Y-014439X0250Y    R090 S1      
327GND              J14   -39         A01X-059411Y-014939X0250Y    R090 S1      
327GND              J14   -84         A01X-060911Y-011939X0250Y    R090 S1      
327GND              J14   -86         A01X-059911Y-011939X0250Y    R090 S1      
327GND              J14   -79         A01X-059411Y-012439X0250Y    R090 S1      
327GND              J14   -77         A01X-060411Y-012439X0250Y    R090 S1      
327GND              J14   -71         A01X-059411Y-012939X0250Y    R090 S1      
327GND              J14   -69         A01X-060411Y-012939X0250Y    R090 S1      
327GND              J14   -92         A01X-060911Y-011439X0250Y    R090 S1      
327GND              J14   -109        A01X-060411Y-010439X0250Y    R090 S1      
327GND              J14   -103        A01X-059411Y-010939X0250Y    R090 S1      
327GND              J14   -101        A01X-060411Y-010939X0250Y    R090 S1      
327GND              J14   -94         A01X-059911Y-011439X0250Y    R090 S1      
327GND              J14   -124        A01X-060911Y-009439X0250Y    R090 S1      
327GND              J14   -116        A01X-060911Y-009939X0250Y    R090 S1      
327GND              J14   -135        A01X-059411Y-008939X0250Y    R090 S1      
327GND              J14   -133        A01X-060411Y-008939X0250Y    R090 S1      
327GND              J14   -126        A01X-059911Y-009439X0250Y    R090 S1      
327GND              J14   -118        A01X-059911Y-009939X0250Y    R090 S1      
327GND              J14   -111        A01X-059411Y-010439X0250Y    R090 S1      
327GND              J14   -141        A01X-060411Y-008439X0250Y    R090 S1      
327GND              J14   -32         A01X-058911Y-015439X0250Y    R090 S1      
327GND              J14   -24         A01X-058911Y-015939X0250Y    R090 S1      
327GND              J14   -64         A01X-058911Y-013439X0250Y    R090 S1      
327GND              J14   -56         A01X-058911Y-013939X0250Y    R090 S1      
327GND              J14   -88         A01X-058911Y-011939X0250Y    R090 S1      
327GND              J14   -96         A01X-058911Y-011439X0250Y    R090 S1      
327GND              J14   -128        A01X-058911Y-009439X0250Y    R090 S1      
327GND              J14   -120        A01X-058911Y-009939X0250Y    R090 S1      
327GND              J14   -26         A01X-061911Y-015439X0250Y    R090 S1      
327GND              J14   -18         A01X-061911Y-015939X0250Y    R090 S1      
327GND              J14   -9          A01X-062411Y-016439X0250Y    R090 S1      
327GND              J14   -1          A01X-062411Y-016939X0250Y    R090 S1      
327GND              J14   -97         A01X-062411Y-010939X0250Y    R090 S1      
327GND              J14   -105        A01X-062411Y-010439X0250Y    R090 S1      
327GND              J14   -129        A01X-062411Y-008939X0250Y    R090 S1      
327GND              J14   -122        A01X-061911Y-009439X0250Y    R090 S1      
327GND              J14   -114        A01X-061911Y-009939X0250Y    R090 S1      
327GND              J14   -82         A01X-061911Y-011939X0250Y    R090 S1      
327GND              J14   -90         A01X-061911Y-011439X0250Y    R090 S1      
327GND              J14   -58         A01X-061911Y-013439X0250Y    R090 S1      
327GND              J14   -50         A01X-061911Y-013939X0250Y    R090 S1      
317GND              VIA   -    MD0100PA00X-007492Y-017150X0220Y         S0      
327GND              R71   -1   M      A01X-007840Y-017144X0280Y0320R270 S1      
317GND              J13   -P8  MD0200PA00X-073016Y-009591X0320Y    R180 S3      
317GND              J13   -P6  MD0200PA00X-071441Y-009591X0320Y    R180 S3      
317GND              J13   -P4  MD0200PA00X-069866Y-009591X0320Y    R180 S3      
317GND              J13   -P2  MD0200PA00X-068291Y-009591X0320Y    R180 S3      
317GND              J13   -P10 MD0200PA00X-074591Y-009591X0320Y    R180 S3      
317GND              J13   -O9  MD0200PA00X-073803Y-010102X0320Y    R180 S3      
317GND              J13   -O7  MD0200PA00X-072228Y-010102X0320Y    R180 S3      
317GND              J13   -O5  MD0200PA00X-070654Y-010102X0320Y    R180 S3      
317GND              J13   -O3  MD0200PA00X-069079Y-010102X0320Y    R180 S3      
317GND              J13   -O1  MD0200PA00X-067504Y-010102X0320Y    R180 S3      
317GND              J13   -N9  MD0200PA00X-073803Y-010654X0320Y    R180 S3      
317GND              J13   -M9  MD0200PA00X-073803Y-011205X0320Y    R180 S3      
317GND              J13   -M8  MD0200PA00X-073016Y-011244X0320Y    R180 S3      
317GND              J13   -M6  MD0200PA00X-071441Y-011244X0320Y    R180 S3      
317GND              J13   -M4  MD0200PA00X-069866Y-011244X0320Y    R180 S3      
317GND              J13   -M2  MD0200PA00X-068291Y-011244X0320Y    R180 S3      
317GND              J13   -M10 MD0200PA00X-074591Y-011244X0320Y    R180 S3      
317GND              J13   -L9  MD0200PA00X-073803Y-011756X0320Y    R180 S3      
317GND              J13   -L7  MD0200PA00X-072228Y-011756X0320Y    R180 S3      
317GND              J13   -L5  MD0200PA00X-070654Y-011756X0320Y    R180 S3      
317GND              J13   -L3  MD0200PA00X-069079Y-011756X0320Y    R180 S3      
317GND              J13   -L1  MD0200PA00X-067504Y-011756X0320Y    R180 S3      
317GND              J13   -J8  MD0200PA00X-073016Y-012898X0320Y    R180 S3      
317GND              J13   -J6  MD0200PA00X-071441Y-012898X0320Y    R180 S3      
317GND              J13   -J4  MD0200PA00X-069866Y-012898X0320Y    R180 S3      
317GND              J13   -J2  MD0200PA00X-068291Y-012898X0320Y    R180 S3      
317GND              J13   -I9  MD0200PA00X-073803Y-013409X0320Y    R180 S3      
317GND              J13   -I7  MD0200PA00X-072228Y-013409X0320Y    R180 S3      
317GND              J13   -I5  MD0200PA00X-070654Y-013409X0320Y    R180 S3      
317GND              J13   -I3  MD0200PA00X-069079Y-013409X0320Y    R180 S3      
317GND              J13   -I1  MD0200PA00X-067504Y-013409X0320Y    R180 S3      
327GND              U1    -P1-P       A01X-148071Y+000469X3720Y2480R180 S1      
327GND              U1    -P5-P       A01X-152071Y+000469X3720Y2480R180 S1      
317GND              VIA   -    MD0100PA00X-145000Y-016250X0220Y         S0      
317GND              VIA   -    MD0100PA00X-145000Y-013750X0220Y         S0      
317GND              VIA   -    M      A01X-145000Y-011250X0220Y         S2      
017GND              VIA   -    M      A08X-145000Y-011250X0320Y         S2      
017GND                    -    MD0100PA00X-145000Y-011250                       
317GND              VIA   -    MD0100PA00X-145000Y-008750X0220Y         S0      
317GND              VIA   -    M      A01X-143750Y-017500X0220Y         S2      
017GND              VIA   -    M      A08X-143750Y-017500X0320Y         S2      
017GND                    -    MD0100PA00X-143750Y-017500                       
317GND              VIA   -    MD0100PA00X-134320Y-008270X0220Y         S0      
317GND              VIA   -    MD0100PA00X-143650Y-008750X0220Y         S0      
317GND              VIA   -    MD0100PA00X-143750Y-010000X0220Y         S0      
317GND              VIA   -    MD0100PA00X-142500Y-016250X0220Y         S0      
317GND              VIA   -    MD0100PA00X-141850Y-009350X0220Y         S0      
317GND              VIA   -    MD0100PA00X-143050Y-009350X0220Y         S0      
317GND              VIA   -    MD0100PA00X-141250Y-006250X0220Y         S0      
317GND              VIA   -    MD0100PA00X-140000Y-016250X0220Y         S0      
317GND              VIA   -    MD0100PA00X-141250Y-017500X0220Y         S0      
317GND              VIA   -    MD0100PA00X-137380Y-005290X0220Y         S0      
317GND              VIA   -    MD0100PA00X-141200Y-010050X0220Y         S0      
317GND              VIA   -    MD0100PA00X-140000Y-011250X0220Y         S0      
317GND              VIA   -    MD0100PA00X-140000Y-007500X0220Y         S0      
317GND              VIA   -    MD0100PA00X-138750Y-006250X0220Y         S0      
317GND              VIA   -    MD0100PA00X-138750Y-017500X0220Y         S0      
317GND              VIA   -    M      A01X-138750Y-015000X0220Y         S2      
017GND              VIA   -    M      A08X-138750Y-015000X0320Y         S2      
017GND                    -    MD0100PA00X-138750Y-015000                       
317GND              VIA   -    MD0100PA00X-138750Y-012500X0220Y         S0      
317GND              VIA   -    MD0100PA00X-137500Y-007500X0220Y         S0      
317GND              VIA   -    MD0100PA00X-136250Y-006250X0220Y         S0      
317GND              VIA   -    MD0100PA00X-135060Y-007500X0220Y         S0      
317GND              VIA   -    MD0100PA00X-133750Y-006250X0220Y         S0      
317GND              VIA   -    MD0100PA00X-125750Y-005750X0220Y         S0      
317GND              VIA   -    MD0100PA00X-124500Y-007000X0220Y         S0      
317GND              VIA   -    MD0100PA00X-124500Y-004500X0220Y         S0      
317GND              VIA   -    MD0100PA00X-124500Y-002000X0220Y         S0      
317GND              VIA   -    MD0100PA00X-123250Y-005750X0220Y         S0      
317GND              VIA   -    MD0100PA00X-113750Y-000250X0220Y         S0      
317GND              VIA   -    MD0100PA00X-112600Y-001500X0220Y         S0      
317GND              VIA   -    MD0100PA00X-111150Y-000250X0220Y         S0      
317GND              VIA   -    MD0100PA00X-092250Y-004500X0220Y         S0      
317GND              VIA   -    MD0100PA00X-092250Y-002000X0220Y         S0      
317GND              VIA   -    MD0100PA00X-092250Y+000500X0220Y         S0      
317GND              VIA   -    MD0100PA00X-091000Y-005750X0220Y         S0      
317GND              VIA   -    MD0100PA00X-089750Y-004500X0220Y         S0      
317GND              VIA   -    MD0100PA00X-091000Y-000750X0220Y         S0      
317GND              VIA   -    MD0100PA00X-089750Y-002000X0220Y         S0      
317GND              VIA   -    MD0100PA00X-089750Y+000500X0220Y         S0      
317GND              VIA   -    MD0100PA00X-088500Y-005750X0220Y         S0      
317GND              VIA   -    MD0100PA00X-088500Y-000750X0220Y         S0      
317GND              VIA   -    MD0100PA00X-087250Y-004500X0220Y         S0      
317GND              VIA   -    MD0100PA00X-087250Y+000500X0220Y         S0      
317GND              VIA   -    MD0100PA00X-086000Y-005750X0220Y         S0      
317GND              VIA   -    MD0100PA00X-086000Y-000750X0220Y         S0      
317GND              VIA   -    MD0100PA00X-083500Y-005750X0220Y         S0      
317GND              VIA   -    MD0100PA00X-084750Y-004500X0220Y         S0      
317GND              VIA   -    MD0100PA00X-084750Y-002000X0220Y         S0      
317GND              VIA   -    MD0100PA00X-084750Y+000500X0220Y         S0      
317GND              VIA   -    MD0100PA00X-082250Y-004500X0220Y         S0      
317GND              VIA   -    MD0100PA00X-082250Y-002000X0220Y         S0      
317GND              VIA   -    MD0100PA00X-082250Y+000500X0220Y         S0      
317GND              VIA   -    MD0100PA00X-081000Y-000750X0220Y         S0      
317GND              VIA   -    MD0100PA00X-078500Y-000750X0220Y         S0      
317GND              VIA   -    MD0100PA00X-079750Y-002000X0220Y         S0      
317GND              VIA   -    MD0100PA00X-079750Y+000500X0220Y         S0      
317GND              VIA   -    MD0100PA00X-077250Y-004500X0220Y         S0      
317GND              VIA   -    MD0100PA00X-077250Y-002000X0220Y         S0      
317GND              VIA   -    MD0100PA00X-077250Y+000500X0220Y         S0      
317GND              VIA   -    MD0100PA00X-076000Y-005750X0220Y         S0      
317GND              VIA   -    MD0100PA00X-076000Y-000750X0220Y         S0      
317GND              VIA   -    MD0100PA00X-073500Y-005750X0220Y         S0      
317GND              VIA   -    MD0100PA00X-074750Y-004500X0220Y         S0      
317GND              VIA   -    MD0100PA00X-074750Y-002000X0220Y         S0      
317GND              VIA   -    MD0100PA00X-073500Y-000750X0220Y         S0      
317GND              VIA   -    MD0100PA00X-074750Y+000500X0220Y         S0      
317GND              VIA   -    MD0100PA00X-072250Y-004500X0220Y         S0      
317GND              VIA   -    MD0100PA00X-072250Y-002000X0220Y         S0      
317GND              VIA   -    MD0100PA00X-072250Y+000500X0220Y         S0      
317GND              VIA   -    MD0100PA00X-071000Y-000750X0220Y         S0      
317GND              VIA   -    MD0100PA00X-069750Y-004500X0220Y         S0      
317GND              VIA   -    MD0100PA00X-069750Y-002000X0220Y         S0      
317GND              VIA   -    MD0100PA00X-068500Y-000750X0220Y         S0      
317GND              VIA   -    MD0100PA00X-069750Y+000500X0220Y         S0      
317GND              VIA   -    MD0100PA00X-067250Y-004500X0220Y         S0      
317GND              VIA   -    MD0100PA00X-067250Y-002000X0220Y         S0      
317GND              VIA   -    MD0100PA00X-067250Y+000500X0220Y         S0      
317GND              VIA   -    MD0100PA00X-057750Y-017750X0220Y         S0      
317GND              VIA   -    MD0100PA00X-057750Y-015250X0220Y         S0      
317GND              VIA   -    MD0100PA00X-057750Y-012750X0220Y         S0      
317GND              VIA   -    MD0100PA00X-065550Y-000050X0220Y         S0      
317GND              VIA   -    MD0100PA00X-065550Y-001250X0220Y         S0      
317GND              VIA   -    MD0100PA00X-055250Y-017750X0220Y         S0      
317GND              VIA   -    MD0100PA00X-056500Y-016500X0220Y         S0      
317GND              VIA   -    MD0100PA00X-055250Y-015250X0220Y         S0      
317GND              VIA   -    MD0100PA00X-056500Y-014000X0220Y         S0      
317GND              VIA   -    MD0100PA00X-061600Y-001250X0220Y         S0      
317GND              VIA   -    MD0100PA00X-063000Y-002550X0220Y         S0      
317GND              VIA   -    MD0100PA00X-065550Y-003750X0220Y         S0      
317GND              VIA   -    MD0100PA00X-063000Y-001250X0220Y         S0      
317GND              VIA   -    MD0100PA00X-061600Y-003750X0220Y         S0      
317GND              VIA   -    MD0100PA00X-056500Y-006500X0220Y         S0      
317GND              VIA   -    MD0100PA00X-054000Y-016500X0220Y         S0      
317GND              VIA   -    MD0100PA00X-054000Y-014000X0220Y         S0      
317GND              VIA   -    MD0100PA00X-054000Y-011500X0220Y         S0      
317GND              VIA   -    MD0100PA00X-054000Y-009000X0220Y         S0      
317GND              VIA   -    MD0100PA00X-054000Y-006500X0220Y         S0      
317GND              VIA   -    MD0100PA00X-052750Y-017750X0220Y         S0      
317GND              VIA   -    MD0100PA00X-052750Y-015250X0220Y         S0      
317GND              VIA   -    MD0100PA00X-052750Y-012750X0220Y         S0      
317GND              VIA   -    MD0100PA00X-052750Y-010250X0220Y         S0      
317GND              VIA   -    MD0100PA00X-052750Y-007750X0220Y         S0      
317GND              VIA   -    MD0100PA00X-051500Y-016500X0220Y         S0      
317GND              VIA   -    MD0100PA00X-051500Y-014000X0220Y         S0      
317GND              VIA   -    MD0100PA00X-051500Y-011500X0220Y         S0      
317GND              VIA   -    MD0100PA00X-050250Y-010250X0220Y         S0      
317GND              VIA   -    MD0100PA00X-050250Y-007750X0220Y         S0      
317GND              VIA   -    MD0100PA00X-051500Y-009000X0220Y         S0      
317GND              VIA   -    MD0100PA00X-051500Y-006500X0220Y         S0      
317GND              VIA   -    MD0100PA00X-049000Y-009000X0220Y         S0      
317GND              VIA   -    MD0100PA00X-057750Y-003750X0220Y         S0      
317GND              VIA   -    MD0100PA00X-057750Y-001250X0220Y         S0      
317GND              VIA   -    MD0100PA00X-056500Y-002500X0220Y         S0      
317GND              VIA   -    MD0100PA00X-056500Y+000000X0220Y         S0      
317GND              VIA   -    MD0100PA00X-055250Y-003750X0220Y         S0      
317GND              VIA   -    MD0100PA00X-054000Y-002500X0220Y         S0      
317GND              VIA   -    MD0100PA00X-055250Y-001250X0220Y         S0      
317GND              VIA   -    MD0100PA00X-054000Y+000000X0220Y         S0      
317GND              VIA   -    MD0100PA00X-052750Y-003750X0220Y         S0      
317GND              VIA   -    MD0100PA00X-052750Y-001250X0220Y         S0      
317GND              VIA   -    MD0100PA00X-051500Y-002500X0220Y         S0      
317GND              VIA   -    MD0100PA00X-051500Y+000000X0220Y         S0      
317GND              VIA   -    MD0100PA00X-050250Y-003750X0220Y         S0      
317GND              VIA   -    M      A01X-050250Y-001250X0220Y         S2      
017GND              VIA   -    M      A08X-050250Y-001250X0320Y         S2      
017GND                    -    MD0100PA00X-050250Y-001250                       
317GND              VIA   -    MD0100PA00X-057750Y+001250X0220Y         S0      
317GND              VIA   -    MD0100PA00X-055250Y+001250X0220Y         S0      
317GND              VIA   -    MD0100PA00X-052750Y+001250X0220Y         S0      
317GND              VIA   -    MD0100PA00X-050250Y+001250X0220Y         S0      
317GND              VIA   -    MD0100PA00X-060250Y-003750X0220Y         S0      
317GND              VIA   -    MD0100PA00X-060250Y-001250X0220Y         S0      
317GND              VIA   -    MD0100PA00X-060250Y+001250X0220Y         S0      
317GND              VIA   -    MD0100PA00X-059000Y-002500X0220Y         S0      
317GND              VIA   -    MD0100PA00X-059000Y+000000X0220Y         S0      
317GND              VIA   -    MD0100PA00X-049000Y+000000X0220Y         S0      
317GND              VIA   -    MD0100PA00X-047750Y-003750X0220Y         S0      
317GND              VIA   -    MD0100PA00X-047750Y+001250X0220Y         S0      
317GND              VIA   -    MD0100PA00X-046500Y-002500X0220Y         S0      
317GND              VIA   -    MD0100PA00X-045250Y+001250X0220Y         S0      
317GND              VIA   -    MD0100PA00X-042750Y+001250X0220Y         S0      
317GND              VIA   -    MD0100PA00X-040250Y+001250X0220Y         S0      
317GND              VIA   -    MD0100PA00X-037750Y+001250X0220Y         S0      
317GND              VIA   -    MD0100PA00X-035250Y+001250X0220Y         S0      
317GND              VIA   -    MD0100PA00X-032750Y+001250X0220Y         S0      
317GND              VIA   -    MD0100PA00X-030250Y+001250X0220Y         S0      
317GND              VIA   -    MD0100PA00X-027750Y+001250X0220Y         S0      
317GND              VIA   -    MD0100PA00X-025250Y+001250X0220Y         S0      
317GND              VIA   -    MD0100PA00X-022750Y+001250X0220Y         S0      
317GND              VIA   -    MD0100PA00X-020250Y+001250X0220Y         S0      
317GND              VIA   -    MD0100PA00X-017750Y+001250X0220Y         S0      
317GND              VIA   -    MD0100PA00X-015250Y+001250X0220Y         S0      
317GND              VIA   -    MD0100PA00X-011500Y+001250X0220Y         S0      
317GND              VIA   -    MD0100PA00X-009000Y+001250X0220Y         S0      
317GND              VIA   -    MD0100PA00X-006500Y+001250X0220Y         S0      
317GND              VIA   -    MD0100PA00X-004000Y+001250X0220Y         S0      
317GND              VIA   -    MD0100PA00X-001500Y+001250X0220Y         S0      
317GND              VIA   -    M      A01X-101250Y-000750X0220Y         S2      
017GND              VIA   -    M      A08X-101250Y-000750X0320Y         S2      
017GND                    -    MD0100PA00X-101250Y-000750                       
317GND              VIA   -    MD0100PA00X-142000Y+001450X0220Y         S0      
317GND              VIA   -    MD0100PA00X-139552Y+001405X0220Y         S0      
317GND              VIA   -    MD0100PA00X-137000Y+001450X0220Y         S0      
317GND              VIA   -    MD0100PA00X-134500Y+001450X0220Y         S0      
317GND              VIA   -    MD0100PA00X-132000Y+001450X0220Y         S0      
317GND              VIA   -    MD0100PA00X-129500Y+001450X0220Y         S0      
317GND              VIA   -    MD0100PA00X-127000Y+001450X0220Y         S0      
317GND              VIA   -    MD0100PA00X-124500Y+001450X0220Y         S0      
317GND              VIA   -    MD0100PA00X-122000Y+001450X0220Y         S0      
317GND              VIA   -    MD0100PA00X-119500Y+001450X0220Y         S0      
317GND              VIA   -    MD0100PA00X-117000Y+001450X0220Y         S0      
317GND              VIA   -    MD0100PA00X-114500Y+001450X0220Y         S0      
317GND              VIA   -    MD0100PA00X-112000Y+001450X0220Y         S0      
317GND              VIA   -    MD0100PA00X-109500Y+001450X0220Y         S0      
317GND              VIA   -    MD0100PA00X-103250Y+001450X0220Y         S0      
317GND              VIA   -    MD0100PA00X-100750Y+001450X0220Y         S0      
317GND              VIA   -    MD0100PA00X-098250Y+001450X0220Y         S0      
317GND              VIA   -    MD0100PA00X-095750Y+001450X0220Y         S0      
317GND              VIA   -    MD0100PA00X-093250Y+001450X0220Y         S0      
317GND              VIA   -    M      A01X-026800Y-000050X0220Y         S2      
017GND              VIA   -    M      A08X-026800Y-000050X0320Y         S2      
017GND                    -    MD0100PA00X-026800Y-000050                       
317GND              VIA   -    MD0100PA00X-025550Y-001300X0220Y         S0      
317GND              VIA   -    MD0100PA00X-024300Y-000050X0220Y         S0      
317GND              VIA   -    M      A01X-110000Y-001500X0220Y    R270 S2      
017GND              VIA   -    M      A08X-110000Y-001500X0320Y    R270 S2      
017GND                    -    MD0100PA00X-110000Y-001500                       
317GND              VIA   -    MD0100PA00X-034800Y-001900X0220Y    R270 S0      
317GND              VIA   -    MD0100PA00X-034800Y-004400X0220Y    R270 S0      
317GND              VIA   -    MD0100PA00X+000300Y-007100X0220Y    R270 S0      
317GND              VIA   -    MD0100PA00X-000950Y-007100X0220Y    R270 S0      
317GND              VIA   -    MD0100PA00X-001800Y-017350X0220Y    R270 S0      
317GND              VIA   -    MD0100PA00X-005950Y-009600X0220Y         S0      
317GND              VIA   -    MD0100PA00X-005950Y-007100X0220Y         S0      
317GND              VIA   -    MD0100PA00X-005950Y-004600X0220Y         S0      
317GND              VIA   -    MD0100PA00X-004700Y-008350X0220Y         S0      
317GND              VIA   -    MD0100PA00X-004700Y-005850X0220Y         S0      
317GND              VIA   -    MD0100PA00X-004700Y-003350X0220Y         S0      
317GND              VIA   -    MD0100PA00X-004200Y+000150X0220Y         S0      
317GND              VIA   -    MD0100PA00X-003450Y-007100X0220Y         S0      
317GND              VIA   -    MD0100PA00X-003450Y-004600X0220Y         S0      
317GND              VIA   -    MD0100PA00X-000950Y-009600X0220Y         S0      
317GND              VIA   -    MD0100PA00X-002200Y-005850X0220Y         S0      
317GND              VIA   -    MD0100PA00X-000950Y-004600X0220Y         S0      
317GND              VIA   -    MD0100PA00X-002200Y-003350X0220Y         S0      
317GND              VIA   -    MD0100PA00X-001700Y+000150X0220Y         S0      
317GND              VIA   -    MD0100PA00X+000300Y-010850X0220Y         S0      
317GND              VIA   -    MD0100PA00X+000300Y-005850X0220Y         S0      
317GND              VIA   -    MD0100PA00X+000300Y-003350X0220Y         S0      
317GND              VIA   -    MD0100PA00X-013900Y-002100X0220Y         S0      
317GND              VIA   -    M      A01X-012650Y-000850X0220Y         S2      
017GND              VIA   -    M      A08X-012650Y-000850X0320Y         S2      
017GND                    -    MD0100PA00X-012650Y-000850                       
317GND              VIA   -    MD0100PA00X-010150Y-003350X0220Y         S0      
317GND              VIA   -    MD0100PA00X-011400Y-002100X0220Y         S0      
317GND              VIA   -    MD0100PA00X-010150Y-000850X0220Y         S0      
317GND              VIA   -    MD0100PA00X-008900Y-002100X0220Y         S0      
317GND              VIA   -    MD0100PA00X-007650Y-003350X0220Y         S0      
317GND              VIA   -    MD0100PA00X-007650Y-000850X0220Y         S0      
317GND              VIA   -    MD0100PA00X-003050Y-015850X0220Y         S0      
317GND              VIA   -    MD0100PA00X-004300Y-014600X0220Y         S0      
317GND              VIA   -    MD0100PA00X-001800Y-014600X0220Y         S0      
317GND              VIA   -    MD0100PA00X-038650Y-004400X0220Y         S0      
317GND              VIA   -    MD0100PA00X-038650Y-001900X0220Y         S0      
317GND              VIA   -    MD0100PA00X-037400Y-005650X0220Y         S0      
317GND              VIA   -    MD0100PA00X-036150Y-004400X0220Y         S0      
317GND              VIA   -    M      A01X-037400Y-003150X0220Y         S2      
017GND              VIA   -    M      A08X-037400Y-003150X0320Y         S2      
017GND                    -    MD0100PA00X-037400Y-003150                       
317GND              VIA   -    MD0100PA00X-036150Y-001900X0220Y         S0      
317GND              VIA   -    MD0100PA00X-033600Y-002800X0220Y         S0      
317GND              VIA   -    MD0100PA00X-024300Y-002550X0220Y         S0      
317GND              VIA   -    MD0100PA00X-033600Y-005300X0220Y         S0      
317GND              VIA   -    MD0100PA00X-032350Y-006550X0220Y         S0      
317GND              VIA   -    M      A01X-005950Y-002100X0220Y         S2      
017GND              VIA   -    M      A08X-005950Y-002100X0320Y         S2      
017GND                    -    MD0100PA00X-005950Y-002100                       
317GND              VIA   -    MD0100PA00X-003450Y-002100X0220Y         S0      
317GND              VIA   -    MD0100PA00X-004700Y-000850X0220Y         S0      
317GND              VIA   -    MD0100PA00X-002200Y-000850X0220Y         S0      
317GND              VIA   -    MD0100PA00X-000950Y-002100X0220Y         S0      
317GND              VIA   -    MD0100PA00X+000300Y-000850X0220Y         S0      
317GND              VIA   -    MD0100PA00X-005950Y-017350X0220Y         S0      
317GND              VIA   -    MD0100PA00X-005950Y-014850X0220Y         S0      
317GND              VIA   -    MD0100PA00X-005950Y-012350X0220Y         S0      
317GND              VIA   -    MD0100PA00X-007150Y-015850X0220Y         S0      
317GND              VIA   -    MD0100PA00X-007150Y-013350X0220Y         S0      
317GND              VIA   -    MD0100PA00X-007050Y-010860X0220Y         S0      
317GND              VIA   -    MD0100PA00X-000950Y-012000X0220Y         S0      
317GND              VIA   -    MD0100PA00X-119950Y+000540X0220Y         S0      
317GND              VIA   -    MD0100PA00X-098300Y-000750X0220Y         S0      
317GND              VIA   -    MD0100PA00X-095750Y-000750X0220Y         S0      
317GND              VIA   -    M      A01X-093250Y-000750X0220Y         S2      
017GND              VIA   -    M      A08X-093250Y-000750X0320Y         S2      
017GND                    -    MD0100PA00X-093250Y-000750                       
317GND              VIA   -    MD0100PA00X-163300Y-013550X0220Y         S0      
317GND              VIA   -    M      A01X-165600Y-013500X0220Y         S2      
017GND              VIA   -    M      A08X-165600Y-013500X0320Y         S2      
017GND                    -    MD0100PA00X-165600Y-013500                       
317GND              VIA   -    MD0100PA00X-141950Y-001800X0220Y         S0      
317GND              VIA   -    MD0100PA00X-139450Y-001800X0220Y         S0      
317GND              VIA   -    MD0100PA00X-143500Y+000100X0220Y         S0      
317GND              VIA   -    MD0100PA00X-133250Y-002750X0220Y         S0      
317GND              J9    -7   MD0410PA00X-125374Y-018409X0610Y    R270 S3      
317GND              J9    -6   MD0410PA00X-122539Y-018409X0610Y    R270 S3      
317GND              J21   -7   MD0410PA00X-038366Y-018409X0610Y    R270 S3      
317GND              J21   -6   MD0410PA00X-035531Y-018409X0610Y    R270 S3      
317GND              J9    -8   MD0410PA00X-128248Y-017228X0610Y    R270 S3      
317GND              J21   -8   MD0410PA00X-041240Y-017228X0610Y    R270 S3      
317GND              J9    -1   MD0410PA00X-120768Y-015457X0610Y    R270 S3      
317GND              J21   -1   MD0410PA00X-033760Y-015457X0610Y    R270 S3      
317GND              J9    -9   MD0410PA00X-128248Y-013016X0610Y    R270 S3      
317GND              J21   -9   MD0410PA00X-041240Y-013016X0610Y    R270 S3      
317GND              J27   -4   MD0550PA00X-080685Y-009964X0790Y    R270 S3      
317GND              J27   -2   MD0550PA00X-078520Y-009964X0790Y    R270 S3      
317GND              J12   -7   MD0240PA00X-102500Y-005094X0440Y    R180 S3      
317GND              J24   -7   MD0240PA00X-015492Y-005094X0440Y    R180 S3      
317GND              VIA   -    MD0100PA00X-143150Y-008100X0220Y         S0      
317GND              VIA   -    MD0100PA00X-140050Y-009650X0220Y         S0      
317GND              VIA   -    MD0100PA00X-140625Y-010625X0220Y         S0      
317GND              VIA   -    MD0100PA00X-139500Y-010625X0220Y         S0      
317GND              VIA   -    MD0100PA00X-140625Y-008250X0220Y         S0      
317GND              VIA   -    MD0100PA00X-139375Y-008250X0220Y         S0      
317GND              VIA   -    MD0100PA00X-138125Y-008250X0220Y         S0      
317GND              VIA   -    M      A01X-136875Y-008250X0220Y         S2      
017GND              VIA   -    M      A08X-136875Y-008250X0320Y         S2      
017GND                    -    MD0100PA00X-136875Y-008250                       
317GND              VIA   -    MD0100PA00X-135625Y-008250X0220Y         S0      
317GND              VIA   -    MD0100PA00X-138000Y-010625X0220Y         S0      
317GND              VIA   -    M      A01X-137125Y-011250X0220Y         S2      
017GND              VIA   -    M      A08X-137125Y-011250X0320Y         S2      
017GND                    -    MD0100PA00X-137125Y-011250                       
317GND              VIA   -    MD0100PA00X-136375Y-010625X0220Y         S0      
317GND              VIA   -    M      A01X-142125Y-008125X0220Y         S2      
017GND              VIA   -    M      A08X-142125Y-008125X0320Y         S2      
017GND                    -    MD0100PA00X-142125Y-008125                       
317GND              VIA   -    MD0100PA00X-143000Y-007540X0220Y         S0      
317GND              VIA   -    MD0100PA00X-090950Y+001450X0220Y         S0      
317GND              VIA   -    MD0100PA00X-088500Y+001450X0220Y         S0      
317GND              VIA   -    MD0100PA00X-086000Y+001450X0220Y         S0      
317GND              VIA   -    MD0100PA00X-083550Y+001450X0220Y         S0      
317GND              VIA   -    MD0100PA00X-081000Y+001450X0220Y         S0      
317GND              VIA   -    MD0100PA00X-078500Y+001450X0220Y         S0      
317GND              VIA   -    MD0100PA00X-076000Y+001450X0220Y         S0      
317GND              VIA   -    MD0100PA00X-073500Y+001450X0220Y         S0      
317GND              VIA   -    MD0100PA00X-071000Y+001450X0220Y         S0      
317GND              VIA   -    MD0100PA00X-068500Y+001450X0220Y         S0      
317GND              VIA   -    MD0100PA00X-066000Y+001450X0220Y         S0      
317GND              VIA   -    MD0100PA00X-063250Y+001450X0220Y         S0      
317GND              VIA   -    MD0100PA00X-061600Y+001450X0220Y         S0      
317GND              VIA   -    M      A01X-112881Y-010417X0220Y         S2      
017GND              VIA   -    M      A08X-112881Y-010417X0320Y         S2      
017GND                    -    MD0100PA00X-112881Y-010417                       
317GND              VIA   -    MD0100PA00X-109901Y-010418X0220Y         S0      
317GND              VIA   -    MD0100PA00X-112040Y-012900X0220Y         S0      
317GND              VIA   -    MD0100PA00X-112480Y-012900X0220Y         S0      
317GND              VIA   -    MD0100PA00X-022893Y-010418X0220Y         S0      
317GND              VIA   -    MD0100PA00X-025472Y-012900X0220Y         S0      
317GND              VIA   -    MD0100PA00X-025032Y-012900X0220Y         S0      
317GND              J21   -4   MD0410PA00X-033760Y-004157X0610Y    R270 S3      
327GND              U1    -P25-       A08X-152071Y+000469X3720Y2480R180 S2      
327GND              U1    -P29-       A08X-148071Y+000469X3720Y2480R180 S2      
317GND              VIA   -    MD0100PA00X-004250Y-017350X0220Y         S0      
317GND              VIA   -    MD0100PA00X-005950Y-016100X0220Y         S0      
317GND              VIA   -    MD0100PA00X-004300Y-015850X0220Y         S0      
317GND              VIA   -    MD0100PA00X-001800Y-015850X0220Y         S0      
317GND              VIA   -    MD0100PA00X-007150Y-014600X0220Y         S0      
317GND              VIA   -    MD0100PA00X-005950Y-013600X0220Y         S0      
317GND              VIA   -    MD0100PA00X-003050Y-014600X0220Y         S0      
317GND              VIA   -    MD0100PA00X-007170Y-012100X0220Y         S0      
317GND              VIA   -    MD0100PA00X+000300Y-012000X0220Y         S0      
317GND              VIA   -    M      A01X-005950Y-010850X0220Y         S2      
017GND              VIA   -    M      A08X-005950Y-010850X0320Y         S2      
017GND                    -    MD0100PA00X-005950Y-010850                       
317GND              VIA   -    MD0100PA00X-000950Y-010850X0220Y         S0      
317GND              VIA   -    MD0100PA00X-000935Y-008350X0220Y         S0      
317GND              VIA   -    M      A01X+000300Y-009600X0220Y         S2      
017GND              VIA   -    M      A08X+000300Y-009600X0320Y         S2      
017GND                    -    MD0100PA00X+000300Y-009600                       
317GND              VIA   -    MD0100PA00X-005950Y-008350X0220Y         S0      
317GND              VIA   -    M      A01X-003450Y-008350X0220Y         S2      
017GND              VIA   -    M      A08X-003450Y-008350X0320Y         S2      
017GND                    -    MD0100PA00X-003450Y-008350                       
317GND              VIA   -    MD0100PA00X-004700Y-007100X0220Y         S0      
317GND              VIA   -    M      A01X-005950Y-005850X0220Y         S2      
017GND              VIA   -    M      A08X-005950Y-005850X0320Y         S2      
017GND                    -    MD0100PA00X-005950Y-005850                       
317GND              VIA   -    MD0100PA00X-003450Y-005850X0220Y         S0      
317GND              VIA   -    M      A01X-000950Y-005850X0220Y         S2      
017GND              VIA   -    M      A08X-000950Y-005850X0320Y         S2      
017GND                    -    MD0100PA00X-000950Y-005850                       
317GND              VIA   -    MD0100PA00X-004700Y-004600X0220Y         S0      
317GND              VIA   -    MD0100PA00X-002200Y-004600X0220Y         S0      
317GND              VIA   -    MD0100PA00X+000300Y-004600X0220Y         S0      
317GND              VIA   -    MD0100PA00X-011400Y-003350X0220Y         S0      
317GND              VIA   -    MD0100PA00X-005950Y-003350X0220Y         S0      
317GND              VIA   -    MD0100PA00X-003450Y-003350X0220Y         S0      
317GND              VIA   -    MD0100PA00X-000950Y-003350X0220Y         S0      
317GND              VIA   -    MD0100PA00X-013900Y-000850X0220Y         S0      
317GND              VIA   -    MD0100PA00X-011400Y-000850X0220Y         S0      
317GND              VIA   -    MD0100PA00X-012650Y-002100X0220Y         S0      
317GND              VIA   -    MD0100PA00X-010150Y-002100X0220Y         S0      
317GND              VIA   -    MD0100PA00X-008900Y-000850X0220Y         S0      
317GND              VIA   -    MD0100PA00X-007650Y-002100X0220Y         S0      
317GND              VIA   -    MD0100PA00X-005950Y-000850X0220Y         S0      
317GND              VIA   -    MD0100PA00X-003450Y-000850X0220Y         S0      
317GND              VIA   -    MD0100PA00X-004700Y-002100X0220Y         S0      
317GND              VIA   -    MD0100PA00X-002200Y-002100X0220Y         S0      
317GND              VIA   -    MD0100PA00X-000950Y-000850X0220Y         S0      
317GND              VIA   -    MD0100PA00X+000300Y-002100X0220Y         S0      
317GND              VIA   -    MD0100PA00X-005450Y+000150X0220Y         S0      
317GND              VIA   -    MD0100PA00X-012750Y+001250X0220Y         S0      
317GND              VIA   -    MD0100PA00X-014000Y+001250X0220Y         S0      
317GND              VIA   -    MD0100PA00X-010250Y+001250X0220Y         S0      
317GND              VIA   -    MD0100PA00X-007750Y+001250X0220Y         S0      
317GND              VIA   -    MD0100PA00X-005250Y+001250X0220Y         S0      
317GND              VIA   -    MD0100PA00X-002750Y+001250X0220Y         S0      
317GND              VIA   -    MD0100PA00X-000250Y+001250X0220Y         S0      
327GND              C1    -2   M      A01X-131673Y-008080X0280Y0320R270 S1      
327GND              C13   -2   M      A01X-044813Y-008070X0280Y0320R270 S1      
317GND              VIA   -    MD0100PA00X-002200Y-007100X0220Y    R270 S0      
317GND              VIA   -    MD0100PA00X+000300Y-008350X0220Y    R270 S0      
317GND              VIA   -    M      A01X-038650Y-005650X0220Y         S2      
017GND              VIA   -    M      A08X-038650Y-005650X0320Y         S2      
017GND                    -    MD0100PA00X-038650Y-005650                       
317GND              VIA   -    MD0100PA00X-034800Y-005700X0220Y         S0      
317GND              VIA   -    MD0100PA00X-036150Y-005650X0220Y         S0      
317GND              VIA   -    MD0100PA00X-023000Y-001350X0220Y    R270 S0      
317GND              VIA   -    MD0100PA00X-037400Y-004400X0220Y         S0      
317GND              VIA   -    MD0100PA00X-024300Y-004050X0220Y         S0      
317GND              VIA   -    MD0100PA00X-038650Y-003150X0220Y         S0      
317GND              VIA   -    MD0100PA00X-036150Y-003150X0220Y         S0      
317GND              VIA   -    M      A01X-025550Y-002550X0220Y         S2      
017GND              VIA   -    M      A08X-025550Y-002550X0320Y         S2      
017GND                    -    MD0100PA00X-025550Y-002550                       
317GND              VIA   -    M      A01X-034800Y-003150X0220Y    R270 S2      
017GND              VIA   -    M      A08X-034800Y-003150X0320Y    R270 S2      
017GND                    -    MD0100PA00X-034800Y-003150                       
317GND              VIA   -    MD0100PA00X-037400Y-001900X0220Y         S0      
317GND              VIA   -    MD0100PA00X-033600Y-001550X0220Y         S0      
317GND              VIA   -    MD0100PA00X-026800Y-001300X0220Y         S0      
317GND              VIA   -    MD0100PA00X-024300Y-001300X0220Y         S0      
317GND              VIA   -    M      A01X-038650Y-000550X0220Y    R270 S2      
017GND              VIA   -    M      A08X-038650Y-000550X0320Y    R270 S2      
017GND                    -    MD0100PA00X-038650Y-000550                       
317GND              VIA   -    MD0100PA00X-025550Y-000050X0220Y         S0      
317GND              VIA   -    M      A01X-023050Y-000050X0220Y         S2      
017GND              VIA   -    M      A08X-023050Y-000050X0320Y         S2      
017GND                    -    MD0100PA00X-023050Y-000050                       
317GND              VIA   -    MD0100PA00X-039000Y+001250X0220Y         S0      
317GND              VIA   -    MD0100PA00X-036500Y+001250X0220Y         S0      
317GND              VIA   -    MD0100PA00X-034000Y+001250X0220Y         S0      
317GND              VIA   -    MD0100PA00X-031500Y+001250X0220Y         S0      
317GND              VIA   -    MD0100PA00X-029000Y+001250X0220Y         S0      
317GND              VIA   -    MD0100PA00X-026500Y+001250X0220Y         S0      
317GND              VIA   -    MD0100PA00X-024000Y+001250X0220Y         S0      
317GND              VIA   -    MD0100PA00X-021500Y+001250X0220Y         S0      
317GND              VIA   -    MD0100PA00X-016500Y+001250X0220Y         S0      
317GND              VIA   -    MD0100PA00X-133040Y-007490X0220Y         S0      
317GND              VIA   -    MD0100PA00X-079750Y-004500X0220Y         S0      
317GND              VIA   -    MD0100PA00X-081000Y-005750X0220Y         S0      
317GND              VIA   -    MD0100PA00X-079750Y-005750X0220Y         S0      
317GND              VIA   -    MD0100PA00X-078500Y-005750X0220Y         S0      
317GND              VIA   -    MD0100PA00X-002115Y-008360X0220Y         S0      
327GND              R79   -2   M      A01X-130244Y-003020X0280Y0320R180 S1      
317GND              VIA   -    M      A01X-034240Y-008750X0220Y         S2      
017GND              VIA   -    M      A08X-034240Y-008750X0320Y         S2      
017GND                    -    MD0100PA00X-034240Y-008750                       
317GND              VIA   -    MD0100PA00X-035370Y-008760X0220Y         S0      
317GND              VIA   -    MD0100PA00X-036050Y-008710X0220Y         S0      
317GND              VIA   -    MD0100PA00X-034785Y-008705X0220Y         S0      
317GND              VIA   -    MD0100PA00X-028500Y-010310X0220Y         S0      
317GND              VIA   -    MD0100PA00X-028500Y-010740X0220Y         S0      
317GND              VIA   -    MD0100PA00X-129880Y-003020X0220Y         S0      
317GND              VIA   -    MD0100PA00X-081000Y-004500X0220Y         S0      
317GND              VIA   -    MD0100PA00X-078500Y-004500X0220Y         S0      
317GND              J22   -1   MD1560PA00X-018153Y-014500X2200Y    R180 S3      
317GND              J15   -1   MD1560PA00X-048681Y-014500X2200Y    R180 S3      
317GND              J10   -1   MD1560PA00X-105161Y-014500X2200Y    R180 S3      
317GND              J3    -1   MD1560PA00X-135689Y-014500X2200Y    R180 S3      
317GND              VIA   -    MD0100PA00X-165850Y-003100X0220Y         S0      
317GND              VIA   -    MD0100PA00X-041350Y+001250X0220Y         S0      
317GND              U3    -4   MD0400PA00X-079373Y-013823X0540Y    R090 S3      
317GND              U2    -4   MD0400PA00X-164900Y-009788X0540Y    R090 S3      
327GND              R9    -2          A01X-132450Y-002196X0280Y0320R090 S1      
317GND              VIA   -    M      A01X-132450Y-002696X0220Y         S2      
017GND              VIA   -    M      A08X-132450Y-002696X0320Y         S2      
017GND                    -    MD0100PA00X-132450Y-002696                       
327GND              R39   -2   M      A01X-048642Y-002116X0280Y0320R090 S1      
327GND              R37   -2   M      A01X-045442Y-002196X0280Y0320R090 S1      
317GND              VIA   -    MD0100PA00X-048642Y-002616X0220Y         S0      
317GND              VIA   -    MD0100PA00X-045442Y-002696X0220Y         S0      
317GND              VIA   -    MD0100PA00X-138730Y-013320X0220Y         S0      
317GND              MH6   -8   MD0140PA00X+001789Y-016795X0260Y         S3      
317GND              MH6   -7   MD0140PA00X+001489Y-017545X0260Y         S3      
317GND              MH6   -6   MD0140PA00X+000689Y-017895X0260Y         S3      
317GND              MH6   -5   MD0140PA00X-000111Y-017545X0260Y         S3      
317GND              MH6   -4   MD0140PA00X-000411Y-016795X0260Y         S3      
317GND              MH6   -3   MD0140PA00X-000061Y-015995X0260Y         S3      
317GND              MH6   -2   MD0140PA00X+000689Y-015695X0260Y         S3      
317GND              MH6   -1   MD1380PA00X+000689Y-016795X2760Y         S3      
317GND              MH5   -8   MD0140PA00X-016660Y-007874X0260Y         S3      
317GND              MH5   -7   MD0140PA00X-016960Y-008624X0260Y         S3      
317GND              MH5   -6   MD0140PA00X-017760Y-008974X0260Y         S3      
317GND              MH5   -5   MD0140PA00X-018560Y-008624X0260Y         S3      
317GND              MH5   -4   MD0140PA00X-018860Y-007874X0260Y         S3      
317GND              MH5   -3   MD0140PA00X-018510Y-007074X0260Y         S3      
317GND              MH5   -2   MD0140PA00X-017760Y-006774X0260Y         S3      
317GND              MH5   -1   MD1380PA00X-017760Y-007874X2760Y         S3      
317GND              MH4   -8   MD0140PA00X-064164Y-015495X0260Y         S3      
317GND              MH4   -7   MD0140PA00X-064464Y-016245X0260Y         S3      
317GND              MH4   -6   MD0140PA00X-065264Y-016595X0260Y         S3      
317GND              MH4   -5   MD0140PA00X-066064Y-016245X0260Y         S3      
317GND              MH4   -4   MD0140PA00X-066364Y-015495X0260Y         S3      
317GND              MH4   -3   MD0140PA00X-066014Y-014695X0260Y         S3      
317GND              MH4   -2   MD0140PA00X-065264Y-014395X0260Y         S3      
317GND              MH4   -1   MD1380PA00X-065264Y-015495X2760Y         S3      
317GND              MH3   -8   MD0140PA00X-103668Y-007874X0260Y         S3      
317GND              MH3   -7   MD0140PA00X-103968Y-008624X0260Y         S3      
317GND              MH3   -6   MD0140PA00X-104768Y-008974X0260Y         S3      
317GND              MH3   -5   MD0140PA00X-105568Y-008624X0260Y         S3      
317GND              MH3   -4   MD0140PA00X-105868Y-007874X0260Y         S3      
317GND              MH3   -3   MD0140PA00X-105518Y-007074X0260Y         S3      
317GND              MH3   -2   MD0140PA00X-104768Y-006774X0260Y         S3      
317GND              MH3   -1   MD1380PA00X-104768Y-007874X2760Y         S3      
317GND              MH2   -8   MD0140PA00X-151173Y-015495X0260Y         S3      
317GND              MH2   -7   MD0140PA00X-151473Y-016245X0260Y         S3      
317GND              MH2   -6   MD0140PA00X-152273Y-016595X0260Y         S3      
317GND              MH2   -5   MD0140PA00X-153073Y-016245X0260Y         S3      
317GND              MH2   -4   MD0140PA00X-153373Y-015495X0260Y         S3      
317GND              MH2   -3   MD0140PA00X-153023Y-014695X0260Y         S3      
317GND              MH2   -2   MD0140PA00X-152273Y-014395X0260Y         S3      
317GND              MH2   -1   MD1380PA00X-152273Y-015495X2760Y         S3      
317GND              MH1   -8   MD0140PA00X-163491Y-016795X0260Y         S3      
317GND              MH1   -7   MD0140PA00X-163791Y-017545X0260Y         S3      
317GND              MH1   -6   MD0140PA00X-164591Y-017895X0260Y         S3      
317GND              MH1   -5   MD0140PA00X-165391Y-017545X0260Y         S3      
317GND              MH1   -4   MD0140PA00X-165691Y-016795X0260Y         S3      
317GND              MH1   -3   MD0140PA00X-165341Y-015995X0260Y         S3      
317GND              MH1   -2   MD0140PA00X-164591Y-015695X0260Y         S3      
317GND              MH1   -1   MD1380PA00X-164591Y-016795X2760Y         S3      
317GND              MH1   -9   MD0140PA00X-163841Y-015995X0260Y         S3      
317GND              MH3   -9   MD0140PA00X-104018Y-007074X0260Y         S3      
317GND              MH6   -9   MD0140PA00X+001439Y-015995X0260Y         S3      
317GND              MH2   -9   MD0140PA00X-151523Y-014695X0260Y         S3      
317GND              MH5   -9   MD0140PA00X-017010Y-007074X0260Y         S3      
317GND              MH4   -9   MD0140PA00X-064514Y-014695X0260Y         S3      
317GND              VIA   -    MD0100PA00X-138250Y+000700X0220Y         S0      
317GND              VIA   -    MD0100PA00X-135750Y+000700X0220Y         S0      
317GND              VIA   -    MD0100PA00X-133250Y+000700X0220Y         S0      
317GND              VIA   -    MD0100PA00X-130750Y+000700X0220Y         S0      
317GND              VIA   -    MD0100PA00X-139500Y-000050X0220Y         S0      
317GND              VIA   -    MD0100PA00X-137000Y-000050X0220Y         S0      
317GND              VIA   -    MD0100PA00X-134500Y-000050X0220Y         S0      
317GND              VIA   -    MD0100PA00X-132000Y-000050X0220Y         S0      
317GND              VIA   -    MD0100PA00X-138250Y-000800X0220Y         S0      
317GND              VIA   -    MD0100PA00X-135750Y-000800X0220Y         S0      
317GND              VIA   -    MD0100PA00X-092250Y-007000X0220Y         S0      
317GND              VIA   -    MD0100PA00X-089750Y-007000X0220Y         S0      
317GND              VIA   -    MD0100PA00X-087250Y-007000X0220Y         S0      
317GND              VIA   -    MD0100PA00X-084750Y-007000X0220Y         S0      
317GND              VIA   -    MD0100PA00X-082250Y-007000X0220Y         S0      
317GND              VIA   -    MD0100PA00X-081000Y-007000X0220Y         S0      
317GND              VIA   -    MD0100PA00X-079750Y-007000X0220Y         S0      
317GND              VIA   -    MD0100PA00X-078500Y-007000X0220Y         S0      
317GND              VIA   -    MD0100PA00X-077250Y-007000X0220Y         S0      
317GND              VIA   -    MD0100PA00X-092250Y-009500X0220Y         S0      
317GND              VIA   -    MD0100PA00X-089750Y-009500X0220Y         S0      
317GND              VIA   -    MD0100PA00X-084750Y-009500X0220Y         S0      
317GND              VIA   -    MD0100PA00X-082250Y-009500X0220Y         S0      
317GND              VIA   -    MD0100PA00X-077250Y-009500X0220Y         S0      
317GND              VIA   -    MD0100PA00X-092250Y-012000X0220Y         S0      
317GND              VIA   -    MD0100PA00X-082250Y-012000X0220Y         S0      
317GND              VIA   -    MD0100PA00X-081000Y-012000X0220Y         S0      
317GND              VIA   -    MD0100PA00X-079750Y-012000X0220Y         S0      
317GND              VIA   -    MD0100PA00X-077250Y-012000X0220Y         S0      
317GND              VIA   -    MD0100PA00X-082250Y-014500X0220Y         S0      
317GND              VIA   -    MD0100PA00X-081000Y-014500X0220Y         S0      
317GND              VIA   -    MD0100PA00X-077250Y-014500X0220Y         S0      
317GND              VIA   -    MD0100PA00X-092250Y-017000X0220Y         S0      
317GND              VIA   -    MD0100PA00X-089750Y-017000X0220Y         S0      
317GND              VIA   -    MD0100PA00X-087250Y-017000X0220Y         S0      
317GND              VIA   -    MD0100PA00X-084750Y-017000X0220Y         S0      
317GND              VIA   -    MD0100PA00X-082250Y-017000X0220Y         S0      
317GND              VIA   -    MD0100PA00X-081000Y-017000X0220Y         S0      
317GND              VIA   -    MD0100PA00X-077250Y-017000X0220Y         S0      
317GND              VIA   -    MD0100PA00X-091000Y-008250X0220Y         S0      
317GND              VIA   -    MD0100PA00X-088500Y-008250X0220Y         S0      
317GND              VIA   -    MD0100PA00X-086000Y-008250X0220Y         S0      
317GND              VIA   -    MD0100PA00X-083500Y-008250X0220Y         S0      
317GND              VIA   -    MD0100PA00X-076000Y-008250X0220Y         S0      
317GND              VIA   -    MD0100PA00X-091000Y-010750X0220Y         S0      
317GND              VIA   -    MD0100PA00X-088500Y-010750X0220Y         S0      
317GND              VIA   -    MD0100PA00X-086000Y-010750X0220Y         S0      
317GND              VIA   -    MD0100PA00X-083500Y-010750X0220Y         S0      
317GND              VIA   -    MD0100PA00X-076000Y-010750X0220Y         S0      
317GND              VIA   -    MD0100PA00X-091000Y-013250X0220Y         S0      
317GND              VIA   -    MD0100PA00X-088500Y-013250X0220Y         S0      
317GND              VIA   -    MD0100PA00X-086000Y-013250X0220Y         S0      
317GND              VIA   -    MD0100PA00X-083500Y-013250X0220Y         S0      
317GND              VIA   -    MD0100PA00X-081000Y-013250X0220Y         S0      
317GND              VIA   -    MD0100PA00X-076000Y-013250X0220Y         S0      
317GND              VIA   -    MD0100PA00X-091000Y-015950X0220Y         S0      
317GND              VIA   -    MD0100PA00X-088500Y-015950X0220Y         S0      
317GND              VIA   -    MD0100PA00X-086000Y-015950X0220Y         S0      
317GND              VIA   -    MD0100PA00X-083500Y-015950X0220Y         S0      
317GND              VIA   -    MD0100PA00X-081000Y-015750X0220Y         S0      
317GND              VIA   -    MD0100PA00X-116000Y-003850X0220Y         S0      
317GND              VIA   -    M      A01X-123250Y-004500X0220Y         S2      
017GND              VIA   -    M      A08X-123250Y-004500X0320Y         S2      
017GND                    -    MD0100PA00X-123250Y-004500                       
317GND              VIA   -    MD0100PA00X-087250Y-002000X0220Y         S0      
317GND              VIA   -    MD0100PA00X-087250Y-009500X0220Y         S0      
317GND              VIA   -    MD0100PA00X-078550Y-012000X0220Y         S0      
317GND              VIA   -    MD0100PA00X-123559Y-013205X0220Y         S0      
317GND              VIA   -    MD0100PA00X-122779Y-013205X0220Y         S0      
317GND              VIA   -    MD0100PA00X-126406Y-014195X0220Y         S0      
317GND              VIA   -    MD0100PA00X-126559Y-014948X0220Y         S0      
317GND              VIA   -    MD0100PA00X-125613Y-014214X0220Y         S0      
317GND              VIA   -    MD0100PA00X-127339Y-014948X0220Y         S0      
327GND              R77   -2   M      A01X-130756Y-004670X0280Y0320     S1      
317GND              VIA   -    MD0100PA00X-131060Y-004669X0220Y         S0      
327GND              R63   -2   M      A01X-043896Y-002950X0280Y0320     S1      
317GND              VIA   -    MD0100PA00X-044200Y-002948X0220Y         S0      
317GND              VIA   -    MD0100PA00X-014256Y-005606X0220Y         S0      
317GND              VIA   -    MD0100PA00X-012988Y-009071X0220Y         S0      
317GND              VIA   -    MD0100PA00X-012978Y-006089X0220Y         S0      
317GND              VIA   -    MD0100PA00X-013370Y-005606X0220Y         S0      
317GND              VIA   -    MD0100PA00X-014256Y-007087X0220Y         S0      
317GND              VIA   -    MD0100PA00X-014256Y-008589X0220Y         S0      
317GND              VIA   -    MD0100PA00X-013330Y-008699X0220Y         S0      
317GND              VIA   -    MD0100PA00X-013844Y-009139X0220Y         S0      
317GND              VIA   -    MD0100PA00X-014565Y-010055X0220Y         S0      
317GND              VIA   -    MD0100PA00X-008770Y-005770X0220Y         S0      
317GND              VIA   -    MD0100PA00X-009925Y-008589X0220Y         S0      
317GND              VIA   -    MD0100PA00X-009925Y-010085X0220Y         S0      
317GND              VIA   -    MD0100PA00X-009019Y-010105X0220Y         S0      
317GND              VIA   -    MD0100PA00X-008657Y-009071X0220Y         S0      
317GND              VIA   -    MD0100PA00X-008647Y-006089X0220Y         S0      
317GND              VIA   -    MD0100PA00X-008647Y-004592X0220Y         S0      
317GND              VIA   -    MD0100PA00X-009533Y-004592X0220Y         S0      
317GND              VIA   -    MD0100PA00X-009543Y-009071X0220Y         S0      
317GND              VIA   -    MD0100PA00X-010170Y-007380X0220Y         S0      
317GND              VIA   -    MD0100PA00X-008647Y-007585X0220Y         S0      
317GND              VIA   -    MD0100PA00X-013864Y-007600X0220Y         S0      
317GND              VIA   -    MD0100PA00X-009533Y-007585X0220Y         S0      
317GND              VIA   -    MD0100PA00X-014510Y-007410X0220Y         S0      
317GND              VIA   -    MD0100PA00X-101264Y-008589X0220Y         S0      
317GND              VIA   -    MD0100PA00X-101573Y-010055X0220Y         S0      
317GND              VIA   -    MD0100PA00X-099996Y-009071X0220Y         S0      
317GND              VIA   -    MD0100PA00X-100843Y-009140X0220Y         S0      
317GND              VIA   -    MD0100PA00X-096551Y-009071X0220Y         S0      
317GND              VIA   -    MD0100PA00X-096933Y-008589X0220Y         S0      
317GND              VIA   -    MD0100PA00X-096933Y-010085X0220Y         S0      
317GND              VIA   -    MD0100PA00X-096027Y-010105X0220Y         S0      
317GND              VIA   -    MD0100PA00X-095665Y-009071X0220Y         S0      
317GND              VIA   -    MD0100PA00X-101264Y-007087X0220Y         S0      
317GND              VIA   -    MD0100PA00X-101518Y-007410X0220Y         S0      
317GND              VIA   -    MD0100PA00X-099986Y-007585X0220Y         S0      
317GND              VIA   -    MD0100PA00X-100872Y-007600X0220Y         S0      
317GND              VIA   -    MD0100PA00X-096541Y-007585X0220Y         S0      
317GND              VIA   -    MD0100PA00X-097178Y-007380X0220Y         S0      
317GND              VIA   -    MD0100PA00X-095655Y-007585X0220Y         S0      
317GND              VIA   -    MD0100PA00X-101264Y-005606X0220Y         S0      
317GND              VIA   -    MD0100PA00X-100378Y-005606X0220Y         S0      
317GND              VIA   -    MD0100PA00X-099986Y-006089X0220Y         S0      
317GND              VIA   -    MD0100PA00X-095655Y-006089X0220Y         S0      
317GND              VIA   -    MD0100PA00X-096541Y-004592X0220Y         S0      
317GND              VIA   -    MD0100PA00X-095655Y-004592X0220Y         S0      
317GND              VIA   -    MD0100PA00X-014213Y-004129X0220Y         S0      
317GND              VIA   -    MD0100PA00X-012459Y-004150X0220Y         S0      
317GND              VIA   -    MD0100PA00X-012660Y-007541X0220Y         S0      
317GND              VIA   -    MD0100PA00X-008331Y-007536X0220Y         S0      
317GND              VIA   -    MD0100PA00X-012978Y-007600X0220Y         S0      
317GND              VIA   -    MD0100PA00X-095325Y-007534X0220Y         S0      
317GND              VIA   -    MD0100PA00X-100338Y-008699X0220Y         S0      
317GND              VIA   -    MD0100PA00X-095778Y-005770X0220Y         S0      
317GND              VIA   -    MD0100PA00X-101286Y-004125X0220Y         S0      
317GND              VIA   -    MD0100PA00X-099428Y-004089X0220Y         S0      
317GND              VIA   -    MD0100PA00X-099667Y-007546X0220Y         S0      
317GND              VIA   -    M      A01X-062161Y-007689X0220Y         S2      
017GND              VIA   -    M      A08X-062161Y-007689X0320Y         S2      
017GND                    -    MD0100PA00X-062161Y-007689                       
317GND              VIA   -    MD0100PA00X-061661Y-007689X0220Y         S0      
317GND              VIA   -    M      A01X-148669Y-007689X0220Y         S2      
017GND              VIA   -    M      A08X-148669Y-007689X0320Y         S2      
017GND                    -    MD0100PA00X-148669Y-007689                       
317GND              VIA   -    MD0100PA00X-112657Y-013673X0220Y         S0      
317GND              VIA   -    MD0100PA00X-112657Y-014799X0220Y         S0      
317GND              VIA   -    MD0100PA00X-111713Y-014809X0220Y         S0      
317GND              VIA   -    MD0100PA00X-110768Y-013673X0220Y         S0      
317GND              VIA   -    MD0100PA00X-109823Y-013673X0220Y         S0      
317GND              VIA   -    MD0100PA00X-110768Y-014809X0220Y         S0      
317GND              VIA   -    MD0100PA00X-109823Y-014809X0220Y         S0      
317GND              VIA   -    MD0100PA00X-112575Y-015748X0220Y         S0      
317GND              VIA   -    MD0100PA00X-112575Y-015288X0220Y         S0      
317GND              VIA   -    MD0100PA00X-111795Y-015288X0220Y         S0      
317GND              VIA   -    MD0100PA00X-111795Y-015748X0220Y         S0      
317GND              VIA   -    MD0100PA00X-111713Y-013673X0220Y         S0      
317GND              VIA   -    MD0100PA00X-111100Y-011616X0220Y         S0      
317GND              VIA   -    MD0100PA00X-110640Y-012396X0220Y         S0      
317GND              VIA   -    MD0100PA00X-111100Y-012396X0220Y         S0      
317GND              VIA   -    MD0100PA00X-110640Y-011616X0220Y         S0      
317GND              VIA   -    MD0100PA00X-123559Y-013665X0220Y         S0      
317GND              VIA   -    MD0100PA00X-122779Y-013665X0220Y         S0      
317GND              VIA   -    MD0100PA00X-125613Y-014674X0220Y         S0      
317GND              VIA   -    MD0100PA00X-126393Y-014674X0220Y         S0      
317GND              VIA   -    MD0100PA00X-126401Y-018594X0220Y         S0      
317GND              VIA   -    MD0100PA00X-127181Y-018594X0220Y         S0      
317GND              VIA   -    MD0100PA00X-126319Y-017800X0220Y         S0      
317GND              VIA   -    MD0100PA00X-125374Y-017800X0220Y         S0      
317GND              VIA   -    MD0100PA00X-124801Y-019220X0220Y         S0      
317GND              VIA   -    MD0100PA00X-124341Y-019220X0220Y         S0      
317GND              VIA   -    MD0100PA00X-124341Y-018440X0220Y         S0      
317GND              VIA   -    MD0100PA00X-124801Y-018440X0220Y         S0      
317GND              VIA   -    MD0100PA00X-120392Y-016966X0220Y    R090 S0      
317GND              VIA   -    MD0100PA00X-120392Y-016506X0220Y    R090 S0      
317GND              VIA   -    MD0100PA00X-121172Y-016506X0220Y    R090 S0      
317GND              VIA   -    MD0100PA00X-121172Y-016966X0220Y    R090 S0      
317GND              VIA   -    MD0100PA00X-123484Y-017800X0220Y         S0      
317GND              VIA   -    MD0100PA00X-122539Y-017800X0220Y         S0      
317GND              VIA   -    MD0100PA00X-121594Y-017800X0220Y         S0      
317GND              VIA   -    MD0100PA00X-126427Y-018107X0220Y         S0      
317GND              VIA   -    MD0100PA00X-127181Y-018134X0220Y         S0      
317GND              VIA   -    MD0100PA00X-127339Y-015408X0220Y         S0      
317GND              VIA   -    MD0100PA00X-126559Y-015408X0220Y         S0      
317GND              VIA   -    MD0100PA00X-122609Y-015220X0220Y         S0      
317GND              VIA   -    MD0100PA00X-121829Y-015220X0220Y         S0      
317GND              VIA   -    MD0100PA00X-122609Y-014760X0220Y         S0      
317GND              VIA   -    MD0100PA00X-121829Y-014760X0220Y         S0      
317GND              VIA   -    MD0100PA00X-123784Y-018768X0220Y    R090 S0      
317GND              VIA   -    MD0100PA00X-123784Y-018308X0220Y    R090 S0      
317GND              VIA   -    MD0100PA00X-123004Y-018768X0220Y    R090 S0      
317GND              VIA   -    MD0100PA00X-123004Y-018308X0220Y    R090 S0      
317GND              VIA   -    MD0100PA00X-025650Y-013673X0220Y         S0      
317GND              VIA   -    MD0100PA00X-024705Y-013673X0220Y         S0      
317GND              VIA   -    MD0100PA00X-025650Y-014799X0220Y         S0      
317GND              VIA   -    MD0100PA00X-024705Y-014809X0220Y         S0      
317GND              VIA   -    MD0100PA00X-023760Y-014809X0220Y         S0      
317GND              VIA   -    MD0100PA00X-022815Y-014809X0220Y         S0      
317GND              VIA   -    MD0100PA00X-022815Y-013673X0220Y         S0      
317GND              VIA   -    MD0100PA00X-023760Y-013673X0220Y         S0      
317GND              VIA   -    MD0100PA00X-025567Y-015288X0220Y         S0      
317GND              VIA   -    MD0100PA00X-025567Y-015748X0220Y         S0      
317GND              VIA   -    MD0100PA00X-024787Y-015748X0220Y         S0      
317GND              VIA   -    MD0100PA00X-024787Y-015288X0220Y         S0      
317GND              VIA   -    MD0100PA00X-024092Y-012396X0220Y         S0      
317GND              VIA   -    MD0100PA00X-023632Y-012396X0220Y         S0      
317GND              VIA   -    MD0100PA00X-024092Y-011616X0220Y         S0      
317GND              VIA   -    MD0100PA00X-023632Y-011616X0220Y         S0      
317GND              VIA   -    MD0100PA00X-122697Y-015735X0220Y         S0      
317GND              VIA   -    MD0100PA00X-123642Y-015735X0220Y         S0      
317GND              VIA   -    MD0100PA00X-126476Y-015735X0220Y         S0      
317GND              VIA   -    MD0100PA00X-127421Y-015735X0220Y         S0      
317GND              VIA   -    MD0100PA00X-040413Y-015735X0220Y         S0      
317GND              VIA   -    MD0100PA00X-039469Y-015735X0220Y         S0      
317GND              VIA   -    MD0100PA00X-036634Y-015735X0220Y         S0      
317GND              VIA   -    MD0100PA00X-035689Y-015735X0220Y         S0      
317GND              VIA   -    MD0100PA00X-036476Y-017800X0220Y         S0      
317GND              VIA   -    MD0100PA00X-034587Y-017800X0220Y         S0      
317GND              VIA   -    MD0100PA00X-035531Y-017800X0220Y         S0      
317GND              VIA   -    MD0100PA00X-039311Y-017800X0220Y         S0      
317GND              VIA   -    MD0100PA00X-040256Y-017800X0220Y         S0      
317GND              VIA   -    MD0100PA00X-038366Y-017800X0220Y         S0      
317GND              VIA   -    MD0100PA00X-040173Y-018594X0220Y         S0      
317GND              VIA   -    MD0100PA00X-040173Y-018134X0220Y         S0      
317GND              VIA   -    MD0100PA00X-039393Y-018594X0220Y         S0      
317GND              VIA   -    MD0100PA00X-039419Y-018107X0220Y         S0      
317GND              VIA   -    MD0100PA00X-037333Y-018440X0220Y         S0      
317GND              VIA   -    MD0100PA00X-037333Y-019220X0220Y         S0      
317GND              VIA   -    MD0100PA00X-037793Y-019220X0220Y         S0      
317GND              VIA   -    MD0100PA00X-037793Y-018440X0220Y         S0      
317GND              VIA   -    MD0100PA00X-036776Y-018768X0220Y    R090 S0      
317GND              VIA   -    MD0100PA00X-036776Y-018308X0220Y    R090 S0      
317GND              VIA   -    MD0100PA00X-035996Y-018768X0220Y    R090 S0      
317GND              VIA   -    MD0100PA00X-035996Y-018308X0220Y    R090 S0      
317GND              VIA   -    MD0100PA00X-033384Y-016966X0220Y    R090 S0      
317GND              VIA   -    MD0100PA00X-033384Y-016506X0220Y    R090 S0      
317GND              VIA   -    MD0100PA00X-034164Y-016506X0220Y    R090 S0      
317GND              VIA   -    MD0100PA00X-034164Y-016966X0220Y    R090 S0      
317GND              VIA   -    MD0100PA00X-039551Y-015408X0220Y         S0      
317GND              VIA   -    MD0100PA00X-039551Y-014948X0220Y         S0      
317GND              VIA   -    MD0100PA00X-040331Y-015408X0220Y         S0      
317GND              VIA   -    MD0100PA00X-040331Y-014948X0220Y         S0      
317GND              VIA   -    MD0100PA00X-034821Y-015220X0220Y         S0      
317GND              VIA   -    MD0100PA00X-035601Y-015220X0220Y         S0      
317GND              VIA   -    MD0100PA00X-038605Y-014674X0220Y         S0      
317GND              VIA   -    MD0100PA00X-038605Y-014214X0220Y         S0      
317GND              VIA   -    MD0100PA00X-039398Y-014195X0220Y         S0      
317GND              VIA   -    MD0100PA00X-039385Y-014674X0220Y         S0      
317GND              VIA   -    MD0100PA00X-034821Y-014760X0220Y         S0      
317GND              VIA   -    MD0100PA00X-035601Y-014760X0220Y         S0      
317GND              VIA   -    MD0100PA00X-035771Y-013665X0220Y         S0      
317GND              VIA   -    MD0100PA00X-036551Y-013205X0220Y         S0      
317GND              VIA   -    MD0100PA00X-035771Y-013205X0220Y         S0      
317GND              VIA   -    MD0100PA00X-036551Y-013665X0220Y         S0      
327GND              J17   -20  M      A01X-022815Y-014236X0200Y0790R180 S1      
327GND              J17   -17  M      A01X-023760Y-014236X0200Y0790R180 S1      
327GND              J17   -14  M      A01X-024705Y-014236X0200Y0790R180 S1      
327GND              J17   -11  M      A01X-025650Y-014236X0200Y0790R180 S1      
327GND              J17   -1          A01X-022972Y-011008X0200Y0790R180 S1      
327GND              J5    -20  M      A01X-109823Y-014236X0200Y0790R180 S1      
327GND              J5    -17  M      A01X-110768Y-014236X0200Y0790R180 S1      
327GND              J5    -14  M      A01X-111713Y-014236X0200Y0790R180 S1      
327GND              J5    -11  M      A01X-112657Y-014236X0200Y0790R180 S1      
327GND              J5    -10         A01X-112815Y-011008X0200Y0790R180 S1      
327GND              J5    -1          A01X-109980Y-011008X0200Y0790R180 S1      
327GND              J20   -38         A01X-034587Y-017260X0140Y0710R180 S1      
327GND              J20   -35         A01X-035531Y-017260X0140Y0710R180 S1      
327GND              J20   -32         A01X-036476Y-017260X0140Y0710R180 S1      
327GND              J20   -26         A01X-038366Y-017260X0140Y0710R180 S1      
327GND              J20   -23         A01X-039311Y-017260X0140Y0710R180 S1      
327GND              J20   -20         A01X-040256Y-017260X0140Y0710R180 S1      
327GND              J20   -19         A01X-040413Y-016276X0140Y0710R180 S1      
327GND              J20   -16         A01X-039469Y-016276X0140Y0710R180 S1      
327GND              J20   -7          A01X-036634Y-016276X0140Y0710R180 S1      
327GND              J20   -4          A01X-035689Y-016276X0140Y0710R180 S1      
327GND              J8    -38         A01X-121594Y-017260X0140Y0710R180 S1      
327GND              J8    -35         A01X-122539Y-017260X0140Y0710R180 S1      
327GND              J8    -32         A01X-123484Y-017260X0140Y0710R180 S1      
327GND              J8    -26         A01X-125374Y-017260X0140Y0710R180 S1      
327GND              J8    -23         A01X-126319Y-017260X0140Y0710R180 S1      
327GND              J8    -20         A01X-127264Y-017260X0140Y0710R180 S1      
327GND              J8    -19         A01X-127421Y-016276X0140Y0710R180 S1      
327GND              J8    -16         A01X-126476Y-016276X0140Y0710R180 S1      
327GND              J8    -7          A01X-123642Y-016276X0140Y0710R180 S1      
327GND              J8    -4          A01X-122697Y-016276X0140Y0710R180 S1      
327GND              R1    -1          A01X-094850Y-017044X0280Y0320R270 S1      
327GND              C14   -2          A01X-053550Y-012225X0280Y0320R270 S1      
327GND              C16   -2          A01X-051920Y-012370X0200Y0230R180 S1      
327GND              R7    -2          A01X-130756Y-007970X0280Y0320     S1      
327GND              R35   -2          A01X-043896Y-007960X0280Y0320     S1      
327GND              C29   -2          A01X-105923Y-004905X0200Y0230R180 S1      
327GND              C35   -2          A01X-106190Y-003815X0280Y0320R090 S1      
327GND              C30   -2          A01X-106393Y-004830X0280Y0320R270 S1      
327GND              R65   -2          A01X-043384Y-004660X0280Y0320R180 S1      
327GND              R40   -2          A01X-031294Y-004200X0280Y0320R180 S1      
327GND              C23   -2          A01X-019010Y-003845X0280Y0320R090 S1      
327GND              C18   -2          A01X-019235Y-004780X0280Y0320R270 S1      
327GND              C17   -2          A01X-018765Y-004855X0200Y0230R180 S1      
327GND              C31   -2          A01X-105600Y-003730X0200Y0230     S1      
327GND              R33   -2          A01X-031786Y-003640X0280Y0320     S1      
327GND              R51   -2          A01X-029926Y-003250X0280Y0320     S1      
327GND              C19   -2          A01X-018415Y-003815X0200Y0230     S1      
327GND              C36   -2          A01X-106200Y-001455X0280Y0320R090 S1      
327GND              C32   -2          A01X-105600Y-001330X0200Y0230     S1      
327GND              C39   -2          A01X-105065Y-001660X0280Y0320     S1      
327GND              R31   -2          A01X-031799Y-001975X0280Y0320     S1      
327GND              R49   -2          A01X-029899Y-002075X0280Y0320     S1      
327GND              R53   -2          A01X-029401Y-001525X0280Y0320R180 S1      
327GND              C24   -2          A01X-019040Y-001385X0280Y0320R090 S1      
327GND              C20   -2          A01X-018415Y-001265X0200Y0230     S1      
327GND              C27   -2          A01X-017885Y-001650X0280Y0320     S1      
317GND              VIA   -    M      A01X-121752Y-015735X0220Y         S2      
017GND              VIA   -    M      A08X-121752Y-015735X0320Y         S2      
017GND                    -    MD0100PA00X-121752Y-015735                       
327GND              J8    -1          A01X-121752Y-016276X0140Y0710R180 S1      
317GND              VIA   -    M      A01X-125532Y-015735X0220Y         S2      
017GND              VIA   -    M      A08X-125532Y-015735X0320Y         S2      
017GND                    -    MD0100PA00X-125532Y-015735                       
327GND              J8    -13         A01X-125531Y-016276X0140Y0710R180 S1      
317GND              VIA   -    M      A01X-038524Y-015735X0220Y         S2      
017GND              VIA   -    M      A08X-038524Y-015735X0320Y         S2      
017GND                    -    MD0100PA00X-038524Y-015735                       
317GND              VIA   -    M      A01X-034744Y-015735X0220Y         S2      
017GND              VIA   -    M      A08X-034744Y-015735X0320Y         S2      
017GND                    -    MD0100PA00X-034744Y-015735                       
327GND              J20   -13         A01X-038524Y-016276X0140Y0710R180 S1      
327GND              J20   -1          A01X-034744Y-016276X0140Y0710R180 S1      
317GND              VIA   -    M      A01X-025873Y-010417X0220Y         S2      
017GND              VIA   -    M      A08X-025873Y-010417X0320Y         S2      
017GND                    -    MD0100PA00X-025873Y-010417                       
327GND              J17   -10         A01X-025807Y-011008X0200Y0790R180 S1      
317ETH40G_B2_TX3P   VIA   -    MD0100PA00X-036321Y-013435X0220Y         S0      
317ETH40G_B2_TX3P   J19   -A1   D0200PA00X-028756Y-017858X0320Y    R180 S3      
327ETH40G_B2_TX3P   J20   -6          A01X-036319Y-016276X0140Y0710R180 S1      
317ETH40G_B2_TX3N   VIA   -    MD0100PA00X-036001Y-013435X0220Y         S0      
317ETH40G_B2_TX3N   J19   -B1   D0200PA00X-028756Y-017307X0320Y    R180 S3      
327ETH40G_B2_TX3N   J20   -5          A01X-036004Y-016276X0140Y0710R180 S1      
317ETH40G_B2_TX2P   VIA   -    MD0100PA00X-036546Y-018538X0220Y         S0      
317ETH40G_B2_TX2P   J19   -B4   D0200PA00X-031118Y-017346X0320Y    R180 S3      
327ETH40G_B2_TX2P   J20   -33         A01X-036161Y-017260X0140Y0710R180 S1      
317ETH40G_B2_TX2N   VIA   -    MD0100PA00X-036226Y-018538X0220Y         S0      
317ETH40G_B2_TX2N   J19   -C4   D0200PA00X-031118Y-016795X0320Y    R180 S3      
327ETH40G_B2_TX2N   J20   -34         A01X-035846Y-017260X0140Y0710R180 S1      
317ETH40G_B2_TX1P   VIA   -    MD0100PA00X-035371Y-014990X0220Y         S0      
317ETH40G_B2_TX1P   J19   -B6   D0200PA00X-032693Y-017346X0320Y    R180 S3      
327ETH40G_B2_TX1P   J20   -3          A01X-035374Y-016276X0140Y0710R180 S1      
317ETH40G_B2_TX1N   VIA   -    MD0100PA00X-035051Y-014990X0220Y         S0      
317ETH40G_B2_TX1N   J19   -C6   D0200PA00X-032693Y-016795X0320Y    R180 S3      
327ETH40G_B2_TX1N   J20   -2          A01X-035059Y-016276X0140Y0710R180 S1      
317ETH40G_B2_TX0P   VIA   -    MD0100PA00X-033614Y-016736X0220Y         S0      
317ETH40G_B2_TX0P   J19   -H6   D0200PA00X-032693Y-014039X0320Y    R180 S3      
327ETH40G_B2_TX0P   J20   -36         A01X-035217Y-017260X0140Y0710R180 S1      
317ETH40G_B2_TX0N   VIA   -    MD0100PA00X-033934Y-016736X0220Y         S0      
317ETH40G_B2_TX0N   J19   -I6   D0200PA00X-032693Y-013488X0320Y    R180 S3      
327ETH40G_B2_TX0N   J20   -37         A01X-034902Y-017260X0140Y0710R180 S1      
317ETH40G_B2_SDA    VIA   -    MD0100PA00X-038977Y-012722X0220Y         S0      
317ETH40G_B2_SDA    VIA   -    MD0100PA00X-043070Y-006310X0220Y         S0      
327ETH40G_B2_SDA    R67   -2          A01X-043384Y-006310X0280Y0320R180 S1      
317ETH40G_B2_SDA    J19   -E4   D0200PA00X-031118Y-015693X0320Y    R180 S3      
327ETH40G_B2_SDA    J20   -12         A01X-038209Y-016276X0140Y0710R180 S1      
317ETH40G_B2_SCL    VIA   -    MD0100PA00X-038960Y-012364X0220Y         S0      
317ETH40G_B2_SCL    VIA   -    MD0100PA00X-042900Y-005760X0220Y         S0      
327ETH40G_B2_SCL    R68   -2          A01X-043384Y-005760X0280Y0320R180 S1      
317ETH40G_B2_SCL    J19   -F4   D0200PA00X-031118Y-015142X0320Y    R180 S3      
327ETH40G_B2_SCL    J20   -11         A01X-037894Y-016276X0140Y0710R180 S1      
317ETH40G_B2_RX3P   VIA   -    MD0100PA00X-037563Y-018670X0220Y         S0      
317ETH40G_B2_RX3P   J19   -B2   D0200PA00X-029543Y-017346X0320Y    R180 S3      
327ETH40G_B2_RX3P   J20   -25         A01X-038681Y-017260X0140Y0710R180 S1      
317ETH40G_B2_RX3N   VIA   -    MD0100PA00X-037563Y-018990X0220Y         S0      
317ETH40G_B2_RX3N   J19   -C2   D0200PA00X-029543Y-016795X0320Y    R180 S3      
327ETH40G_B2_RX3N   J20   -24         A01X-038996Y-017260X0140Y0710R180 S1      
317ETH40G_B2_RX2P   VIA   -    MD0100PA00X-038835Y-014444X0220Y         S0      
317ETH40G_B2_RX2P   J19   -A3   D0200PA00X-030331Y-017858X0320Y    R180 S3      
327ETH40G_B2_RX2P   J20   -14         A01X-038839Y-016276X0140Y0710R180 S1      
317ETH40G_B2_RX2N   VIA   -    MD0100PA00X-039155Y-014444X0220Y         S0      
317ETH40G_B2_RX2N   J19   -B3   D0200PA00X-030331Y-017307X0320Y    R180 S3      
327ETH40G_B2_RX2N   J20   -15         A01X-039154Y-016276X0140Y0710R180 S1      
317ETH40G_B2_RX1P   VIA   -    MD0100PA00X-039623Y-018364X0220Y         S0      
327ETH40G_B2_RX1P   J20   -22         A01X-039626Y-017260X0140Y0710R180 S1      
317ETH40G_B2_RX1P   J19   -A5   D0200PA00X-031906Y-017858X0320Y    R180 S3      
317ETH40G_B2_RX1N   VIA   -    MD0100PA00X-039943Y-018364X0220Y         S0      
327ETH40G_B2_RX1N   J20   -21         A01X-039941Y-017260X0140Y0710R180 S1      
317ETH40G_B2_RX1N   J19   -B5   D0200PA00X-031906Y-017307X0320Y    R180 S3      
317ETH40G_B2_RX0P   VIA   -    MD0100PA00X-039781Y-015178X0220Y         S0      
317ETH40G_B2_RX0P   J19   -E6   D0200PA00X-032693Y-015693X0320Y    R180 S3      
327ETH40G_B2_RX0P   J20   -17         A01X-039783Y-016276X0140Y0710R180 S1      
317ETH40G_B2_RX0N   VIA   -    MD0100PA00X-040101Y-015178X0220Y         S0      
317ETH40G_B2_RX0N   J19   -F6   D0200PA00X-032693Y-015142X0320Y    R180 S3      
327ETH40G_B2_RX0N   J20   -18         A01X-040098Y-016276X0140Y0710R180 S1      
317m0170            VIA   -    MD0100PA00X-044196Y-006860X0220Y         S0      
327m0170            R61   -2          A01X-043896Y-006860X0280Y0320     S1      
317m0170            VIA   -    M      A01X-042940Y-004110X0220Y         S2      
017m0170            VIA   -    M      A08X-042940Y-004110X0320Y         S2      
017m0170                  -    MD0100PA00X-042940Y-004110                       
327m0170            R69   -2          A01X-043384Y-004110X0280Y0320R180 S1      
317m0170            VIA   -    MD0100PA00X-038042Y-014700X0220Y         S0      
327m0170            J20   -9          A01X-037264Y-016276X0140Y0710R180 S1      
317m0171            J19   -H5   D0200PA00X-031906Y-014000X0320Y    R180 S3      
327m0171            R66   -2          A01X-031294Y-004750X0280Y0320R180 S1      
317m0171            VIA   -    MD0100PA00X-030940Y-004770X0220Y         S0      
317m0172            VIA   -    M      A01X-043040Y-003560X0220Y         S2      
017m0172            VIA   -    M      A08X-043040Y-003560X0320Y         S2      
017m0172                  -    MD0100PA00X-043040Y-003560                       
327m0172            R62   -2   M      A01X-043384Y-003560X0280Y0320R180 S1      
317m0172            VIA   -    MD0100PA00X-037362Y-012443X0220Y         S0      
327m0172            R63   -1          A01X-043384Y-002950X0280Y0320R180 S1      
327m0172            J20   -8          A01X-036949Y-016276X0140Y0710R180 S1      
327m0173            R66   -1          A01X-031806Y-004750X0280Y0320     S1      
317m0173            VIA   -    M      A01X-032150Y-004750X0220Y         S2      
017m0173            VIA   -    M      A08X-032150Y-004750X0320Y         S2      
017m0173                  -    MD0100PA00X-032150Y-004750                       
317m0173            VIA   -    MD0100PA00X-033345Y-017495X0220Y         S0      
317m0173            VIA   -    MD0100PA00X-037952Y-018110X0220Y         S0      
327m0173            J20   -27         A01X-038051Y-017260X0140Y0710R180 S1      
327m0174            R65   -1          A01X-043896Y-004660X0280Y0320     S1      
317m0174            VIA   -    M      A01X-044280Y-004660X0220Y         S2      
017m0174            VIA   -    M      A08X-044280Y-004660X0320Y         S2      
017m0174                  -    MD0100PA00X-044280Y-004660                       
327m0174            R70   -2          A01X-044910Y-006896X0280Y0320R090 S1      
317m0174            VIA   -    MD0100PA00X-045270Y-006900X0220Y         S0      
317m0174            VIA   -    MD0100PA00X-040554Y-018308X0220Y         S0      
317m0174            VIA   -    MD0100PA00X-036791Y-017985X0220Y         S0      
327m0174            J20   -31         A01X-036791Y-017260X0140Y0710R180 S1      
317m0175            VIA   -    MD0100PA00X-037790Y-017793X0220Y         S0      
327m0175            R64   -2          A01X-043384Y-005210X0280Y0320R180 S1      
317m0175            VIA   -    M      A01X-043018Y-005210X0220Y         S2      
017m0175            VIA   -    M      A08X-043018Y-005210X0320Y         S2      
017m0175                  -    MD0100PA00X-043018Y-005210                       
317m0175            VIA   -    MD0100PA00X-040554Y-017963X0220Y         S0      
327m0175            J20   -28         A01X-037736Y-017260X0140Y0710R180 S1      
317ETH40G_B1_TX3P   VIA   -    MD0100PA00X-123329Y-013435X0220Y         S0      
317ETH40G_B1_TX3P   J7    -A1   D0200PA00X-115764Y-017858X0320Y    R180 S3      
327ETH40G_B1_TX3P   J8    -6          A01X-123327Y-016276X0140Y0710R180 S1      
317ETH40G_B1_TX3N   VIA   -    MD0100PA00X-123009Y-013435X0220Y         S0      
317ETH40G_B1_TX3N   J7    -B1   D0200PA00X-115764Y-017307X0320Y    R180 S3      
327ETH40G_B1_TX3N   J8    -5          A01X-123012Y-016276X0140Y0710R180 S1      
317ETH40G_B1_TX2P   J7    -B4   D0200PA00X-118126Y-017346X0320Y    R180 S3      
317ETH40G_B1_TX2P   VIA   -    MD0100PA00X-123554Y-018538X0220Y         S0      
327ETH40G_B1_TX2P   J8    -33         A01X-123169Y-017260X0140Y0710R180 S1      
317ETH40G_B1_TX2N   J7    -C4   D0200PA00X-118126Y-016795X0320Y    R180 S3      
317ETH40G_B1_TX2N   VIA   -    MD0100PA00X-123234Y-018538X0220Y         S0      
327ETH40G_B1_TX2N   J8    -34         A01X-122854Y-017260X0140Y0710R180 S1      
317ETH40G_B1_TX1P   VIA   -    MD0100PA00X-122379Y-014990X0220Y         S0      
317ETH40G_B1_TX1P   J7    -B6   D0200PA00X-119701Y-017346X0320Y    R180 S3      
327ETH40G_B1_TX1P   J8    -3          A01X-122382Y-016276X0140Y0710R180 S1      
317ETH40G_B1_TX1N   VIA   -    MD0100PA00X-122059Y-014990X0220Y         S0      
317ETH40G_B1_TX1N   J7    -C6   D0200PA00X-119701Y-016795X0320Y    R180 S3      
327ETH40G_B1_TX1N   J8    -2          A01X-122067Y-016276X0140Y0710R180 S1      
317ETH40G_B1_TX0P   J7    -H6   D0200PA00X-119701Y-014039X0320Y    R180 S3      
317ETH40G_B1_TX0P   VIA   -    MD0100PA00X-120622Y-016736X0220Y         S0      
327ETH40G_B1_TX0P   J8    -36         A01X-122224Y-017260X0140Y0710R180 S1      
317ETH40G_B1_TX0N   J7    -I6   D0200PA00X-119701Y-013488X0320Y    R180 S3      
317ETH40G_B1_TX0N   VIA   -    MD0100PA00X-120942Y-016736X0220Y         S0      
327ETH40G_B1_TX0N   J8    -37         A01X-121909Y-017260X0140Y0710R180 S1      
317ETH40G_B1_SDA    J7    -E4   D0200PA00X-118126Y-015693X0320Y    R180 S3      
317ETH40G_B1_SDA    VIA   -    MD0100PA00X-125066Y-014048X0220Y         S0      
317ETH40G_B1_SDA    VIA   -    MD0100PA00X-129840Y-006320X0220Y         S0      
327ETH40G_B1_SDA    R81   -2          A01X-130244Y-006320X0280Y0320R180 S1      
327ETH40G_B1_SDA    J8    -12         A01X-125217Y-016276X0140Y0710R180 S1      
317ETH40G_B1_SCL    VIA   -    MD0100PA00X-124902Y-014480X0220Y         S0      
317ETH40G_B1_SCL    VIA   -    MD0100PA00X-129800Y-005840X0220Y         S0      
327ETH40G_B1_SCL    R82   -2          A01X-130244Y-005770X0280Y0320R180 S1      
317ETH40G_B1_SCL    J7    -F4   D0200PA00X-118126Y-015142X0320Y    R180 S3      
327ETH40G_B1_SCL    J8    -11         A01X-124902Y-016276X0140Y0710R180 S1      
317ETH40G_B1_RX3P   J7    -B2   D0200PA00X-116551Y-017346X0320Y    R180 S3      
317ETH40G_B1_RX3P   VIA   -    MD0100PA00X-124571Y-018670X0220Y         S0      
327ETH40G_B1_RX3P   J8    -25         A01X-125689Y-017260X0140Y0710R180 S1      
317ETH40G_B1_RX3N   J7    -C2   D0200PA00X-116551Y-016795X0320Y    R180 S3      
317ETH40G_B1_RX3N   VIA   -    MD0100PA00X-124571Y-018990X0220Y         S0      
327ETH40G_B1_RX3N   J8    -24         A01X-126004Y-017260X0140Y0710R180 S1      
317ETH40G_B1_RX2P   VIA   -    MD0100PA00X-125843Y-014444X0220Y         S0      
317ETH40G_B1_RX2P   J7    -A3   D0200PA00X-117339Y-017858X0320Y    R180 S3      
327ETH40G_B1_RX2P   J8    -14         A01X-125846Y-016276X0140Y0710R180 S1      
317ETH40G_B1_RX2N   VIA   -    MD0100PA00X-126163Y-014444X0220Y         S0      
317ETH40G_B1_RX2N   J7    -B3   D0200PA00X-117339Y-017307X0320Y    R180 S3      
327ETH40G_B1_RX2N   J8    -15         A01X-126161Y-016276X0140Y0710R180 S1      
317ETH40G_B1_RX1P   VIA   -    MD0100PA00X-126631Y-018364X0220Y         S0      
327ETH40G_B1_RX1P   J8    -22         A01X-126634Y-017260X0140Y0710R180 S1      
317ETH40G_B1_RX1P   J7    -A5   D0200PA00X-118913Y-017858X0320Y    R180 S3      
317ETH40G_B1_RX1N   VIA   -    MD0100PA00X-126951Y-018364X0220Y         S0      
327ETH40G_B1_RX1N   J8    -21         A01X-126949Y-017260X0140Y0710R180 S1      
317ETH40G_B1_RX1N   J7    -B5   D0200PA00X-118913Y-017307X0320Y    R180 S3      
317ETH40G_B1_RX0P   VIA   -    MD0100PA00X-126789Y-015178X0220Y         S0      
317ETH40G_B1_RX0P   J7    -E6   D0200PA00X-119701Y-015693X0320Y    R180 S3      
327ETH40G_B1_RX0P   J8    -17         A01X-126791Y-016276X0140Y0710R180 S1      
317ETH40G_B1_RX0N   VIA   -    MD0100PA00X-127109Y-015178X0220Y         S0      
317ETH40G_B1_RX0N   J7    -F6   D0200PA00X-119701Y-015142X0320Y    R180 S3      
327ETH40G_B1_RX0N   J8    -18         A01X-127106Y-016276X0140Y0710R180 S1      
317m0176            VIA   -    MD0100PA00X-124886Y-015020X0220Y         S0      
317m0176            VIA   -    MD0100PA00X-131056Y-006870X0220Y         S0      
327m0176            R75   -2          A01X-130756Y-006870X0280Y0320     S1      
327m0176            R83   -2          A01X-130244Y-004120X0280Y0320R180 S1      
317m0176            VIA   -    M      A01X-129800Y-004120X0220Y         S2      
017m0176            VIA   -    M      A08X-129800Y-004120X0320Y         S2      
017m0176                  -    MD0100PA00X-129800Y-004120                       
327m0176            J8    -9          A01X-124272Y-016276X0140Y0710R180 S1      
317m0177            J7    -H5   D0200PA00X-118913Y-014000X0320Y    R180 S3      
327m0177            R80   -2          A01X-118244Y-004650X0280Y0320R180 S1      
317m0177            VIA   -    MD0100PA00X-117890Y-004670X0220Y         S0      
317m0178            VIA   -    MD0100PA00X-123631Y-014039X0220Y         S0      
317m0178            VIA   -    M      A01X-129878Y-005220X0220Y         S2      
017m0178            VIA   -    M      A08X-129878Y-005220X0320Y         S2      
017m0178                  -    MD0100PA00X-129878Y-005220                       
327m0178            R76   -2   M      A01X-130244Y-005220X0280Y0320R180 S1      
327m0178            R77   -1          A01X-130244Y-004670X0280Y0320R180 S1      
327m0178            J8    -8          A01X-123957Y-016276X0140Y0710R180 S1      
317m0179            VIA   -    M      A01X-119100Y-004650X0220Y         S2      
017m0179            VIA   -    M      A08X-119100Y-004650X0320Y         S2      
017m0179                  -    MD0100PA00X-119100Y-004650                       
327m0179            R80   -1          A01X-118756Y-004650X0280Y0320     S1      
317m0179            VIA   -    MD0100PA00X-120258Y-017630X0220Y         S0      
317m0179            VIA   -    MD0100PA00X-125059Y-017992X0220Y         S0      
327m0179            J8    -27         A01X-125059Y-017260X0140Y0710R180 S1      
327m0180            R79   -1          A01X-130756Y-003020X0280Y0320     S1      
317m0180            VIA   -    M      A01X-131120Y-003020X0220Y         S2      
017m0180            VIA   -    M      A08X-131120Y-003020X0320Y         S2      
017m0180                  -    MD0100PA00X-131120Y-003020                       
327m0180            R84   -2          A01X-131770Y-006394X0280Y0320R270 S1      
317m0180            VIA   -    MD0100PA00X-131770Y-006020X0220Y         S0      
317m0180            VIA   -    MD0100PA00X-127943Y-018058X0220Y         S0      
327m0180            J8    -31         A01X-123799Y-017260X0140Y0710R180 S1      
317m0180            VIA   -    MD0100PA00X-123799Y-017985X0220Y         S0      
317m0181            VIA   -    M      A01X-129870Y-003570X0220Y         S2      
017m0181            VIA   -    M      A08X-129870Y-003570X0320Y         S2      
017m0181                  -    MD0100PA00X-129870Y-003570                       
327m0181            R78   -2          A01X-130244Y-003570X0280Y0320R180 S1      
317m0181            VIA   -    MD0100PA00X-124798Y-017793X0220Y         S0      
317m0181            VIA   -    MD0100PA00X-127686Y-017803X0220Y         S0      
327m0181            J8    -28         A01X-124744Y-017260X0140Y0710R180 S1      
317m0182            VIA   -    M      A01X-023287Y-010420X0220Y         S2      
017m0182            VIA   -    M      A08X-023287Y-010420X0320Y         S2      
017m0182                  -    MD0100PA00X-023287Y-010420                       
327m0182            R46   -2          A01X-029387Y-000445X0280Y0320R180 S1      
317m0182            VIA   -    MD0100PA00X-029030Y-000440X0220Y         S0      
327m0182            J17   -2          A01X-023287Y-011008X0200Y0790R180 S1      
317m0183            VIA   -    MD0100PA00X-023602Y-010210X0220Y         S0      
327m0183            R48   -2   M      A01X-029387Y-002595X0280Y0320R180 S1      
327m0183            R49   -1          A01X-029387Y-002075X0280Y0320R180 S1      
317m0183            VIA   -    M      A01X-029080Y-002600X0220Y         S2      
017m0183            VIA   -    M      A08X-029080Y-002600X0320Y         S2      
017m0183                  -    MD0100PA00X-029080Y-002600                       
327m0183            J17   -3          A01X-023602Y-011008X0200Y0790R180 S1      
317ETH10G_B2_TXP    VIA   -    MD0100PA00X-023862Y-012166X0220Y         S0      
317ETH10G_B2_TXP    J19   -G1   D0200PA00X-028756Y-014551X0320Y    R180 S3      
327ETH10G_B2_TXP    J17   -18         A01X-023445Y-014236X0200Y0790R180 S1      
317ETH10G_B2_TXN    VIA   -    MD0100PA00X-023862Y-011846X0220Y         S0      
317ETH10G_B2_TXN    J19   -H1   D0200PA00X-028756Y-014000X0320Y    R180 S3      
327ETH10G_B2_TXN    J17   -19         A01X-023130Y-014236X0200Y0790R180 S1      
317ETH10G_B2_SDA    VIA   -    MD0100PA00X-027810Y-017820X0220Y         S0      
317ETH10G_B2_SDA    VIA   -    MD0100PA00X-023922Y-010420X0220Y         S0      
327ETH10G_B2_SDA    R54   -2          A01X-029926Y-004880X0280Y0320     S1      
317ETH10G_B2_SDA    VIA   -    MD0100PA00X-030320Y-004880X0220Y         S0      
317ETH10G_B2_SDA    J19   -D3   D0200PA00X-030331Y-016205X0320Y    R180 S3      
327ETH10G_B2_SDA    J17   -4          A01X-023917Y-011008X0200Y0790R180 S1      
317ETH10G_B2_SCL    VIA   -    MD0100PA00X-024232Y-010160X0220Y         S0      
317ETH10G_B2_SCL    VIA   -    MD0100PA00X-027440Y-017820X0220Y         S0      
317ETH10G_B2_SCL    VIA   -    MD0100PA00X-030320Y-004330X0220Y         S0      
327ETH10G_B2_SCL    R56   -2          A01X-029926Y-004330X0280Y0320     S1      
317ETH10G_B2_SCL    J19   -E3   D0200PA00X-030331Y-015654X0320Y    R180 S3      
327ETH10G_B2_SCL    J17   -5          A01X-024232Y-011008X0200Y0790R180 S1      
317m0184            VIA   -    M      A01X-025179Y-010433X0220Y         S2      
017m0184            VIA   -    M      A08X-025179Y-010433X0320Y         S2      
017m0184                  -    MD0100PA00X-025179Y-010433                       
317m0184            VIA   -    MD0100PA00X-030790Y-001363X0220Y         S0      
327m0184            R55   -2          A01X-031279Y-001363X0280Y0320R180 S1      
327m0184            J17   -8          A01X-025177Y-011008X0200Y0790R180 S1      
317ETH10G_B2_RXP    VIA   -    MD0100PA00X-025017Y-015518X0220Y         S0      
317ETH10G_B2_RXP    J19   -D1   D0200PA00X-028756Y-016205X0320Y    R180 S3      
327ETH10G_B2_RXP    J17   -13         A01X-025020Y-014236X0200Y0790R180 S1      
317ETH10G_B2_RXN    VIA   -    MD0100PA00X-025337Y-015518X0220Y         S0      
317ETH10G_B2_RXN    J19   -E1   D0200PA00X-028756Y-015654X0320Y    R180 S3      
327ETH10G_B2_RXN    J17   -12         A01X-025335Y-014236X0200Y0790R180 S1      
317ETH10G_B2_RS1    VIA   -    MD0100PA00X-025492Y-010170X0220Y         S0      
327ETH10G_B2_RS1    R53   -1   M      A01X-029913Y-001525X0280Y0320     S1      
327ETH10G_B2_RS1    R52   -2          A01X-029913Y-000975X0280Y0320     S1      
317ETH10G_B2_RS1    VIA   -    M      A01X-030250Y-001520X0220Y         S2      
017ETH10G_B2_RS1    VIA   -    M      A08X-030250Y-001520X0320Y         S2      
017ETH10G_B2_RS1          -    MD0100PA00X-030250Y-001520                       
327ETH10G_B2_RS1    J17   -9          A01X-025492Y-011008X0200Y0790R180 S1      
317ETH10G_B2_RS0    VIA   -    MD0100PA00X-024862Y-010176X0220Y         S0      
327ETH10G_B2_RS0    R51   -1   M      A01X-029414Y-003250X0280Y0320R180 S1      
327ETH10G_B2_RS0    R50   -2          A01X-029414Y-003800X0280Y0320R180 S1      
317ETH10G_B2_RS0    VIA   -    M      A01X-028950Y-003250X0220Y         S2      
017ETH10G_B2_RS0    VIA   -    M      A08X-028950Y-003250X0320Y         S2      
017ETH10G_B2_RS0          -    MD0100PA00X-028950Y-003250                       
327ETH10G_B2_RS0    J17   -7          A01X-024862Y-011008X0200Y0790R180 S1      
317m0185            VIA   -    MD0100PA00X-032180Y-000730X0220Y         S0      
327m0185            R43   -1          A01X-031786Y-000730X0280Y0320     S1      
317m0185            J19   -I2   D0200PA00X-029543Y-013488X0320Y    R180 S3      
317m0186            VIA   -    M      A01X-024541Y-010424X0220Y         S2      
017m0186            VIA   -    M      A08X-024541Y-010424X0320Y         S2      
017m0186                  -    MD0100PA00X-024541Y-010424                       
327m0186            R57   -1          A01X-031274Y-000150X0280Y0320R180 S1      
327m0186            R43   -2   M      A01X-031274Y-000730X0280Y0320R180 S1      
317m0186            VIA   -    MD0100PA00X-030880Y-000740X0220Y         S0      
327m0186            J17   -6          A01X-024547Y-011008X0200Y0790R180 S1      
317m0187            VIA   -    MD0100PA00X-110295Y-010420X0220Y         S0      
317m0187            VIA   -    M      A01X-115970Y-000575X0220Y         S2      
017m0187            VIA   -    M      A08X-115970Y-000575X0320Y         S2      
017m0187                  -    MD0100PA00X-115970Y-000575                       
327m0187            R18   -2          A01X-116337Y-000545X0280Y0320R180 S1      
327m0187            J5    -2          A01X-110295Y-011008X0200Y0790R180 S1      
317m0188            VIA   -    MD0100PA00X-110610Y-010210X0220Y         S0      
317m0188            VIA   -    M      A01X-115870Y-001625X0220Y         S2      
017m0188            VIA   -    M      A08X-115870Y-001625X0320Y         S2      
017m0188                  -    MD0100PA00X-115870Y-001625                       
327m0188            R21   -1          A01X-116337Y-001075X0280Y0320R180 S1      
327m0188            R20   -2   M      A01X-116337Y-001625X0280Y0320R180 S1      
327m0188            J5    -3          A01X-110610Y-011008X0200Y0790R180 S1      
317ETH10G_B1_TXP    J7    -G1   D0200PA00X-115764Y-014551X0320Y    R180 S3      
317ETH10G_B1_TXP    VIA   -    MD0100PA00X-110870Y-012166X0220Y         S0      
327ETH10G_B1_TXP    J5    -18         A01X-110453Y-014236X0200Y0790R180 S1      
317ETH10G_B1_TXN    J7    -H1   D0200PA00X-115764Y-014000X0320Y    R180 S3      
317ETH10G_B1_TXN    VIA   -    MD0100PA00X-110870Y-011846X0220Y         S0      
327ETH10G_B1_TXN    J5    -19         A01X-110138Y-014236X0200Y0790R180 S1      
317ETH10G_B1_SDA    J7    -D3   D0200PA00X-117339Y-016205X0320Y    R180 S3      
327ETH10G_B1_SDA    R26   -2          A01X-116856Y-004950X0280Y0320     S1      
317ETH10G_B1_SDA    VIA   -    MD0100PA00X-117320Y-004970X0220Y         S0      
317ETH10G_B1_SDA    VIA   -    MD0100PA00X-110930Y-010420X0220Y         S0      
327ETH10G_B1_SDA    J5    -4          A01X-110925Y-011008X0200Y0790R180 S1      
317ETH10G_B1_SCL    VIA   -    MD0100PA00X-117250Y-004400X0220Y         S0      
327ETH10G_B1_SCL    R28   -2          A01X-116856Y-004400X0280Y0320     S1      
317ETH10G_B1_SCL    J7    -E3   D0200PA00X-117339Y-015654X0320Y    R180 S3      
317ETH10G_B1_SCL    VIA   -    MD0100PA00X-111240Y-010160X0220Y         S0      
327ETH10G_B1_SCL    J5    -5          A01X-111240Y-011008X0200Y0790R180 S1      
317m0189            VIA   -    M      A01X-112187Y-010433X0220Y         S2      
017m0189            VIA   -    M      A08X-112187Y-010433X0320Y         S2      
017m0189                  -    MD0100PA00X-112187Y-010433                       
327m0189            R27   -2          A01X-118229Y-001213X0280Y0320R180 S1      
317m0189            VIA   -    MD0100PA00X-117780Y-001210X0220Y         S0      
327m0189            J5    -8          A01X-112185Y-011008X0200Y0790R180 S1      
317ETH10G_B1_RXP    VIA   -    MD0100PA00X-112025Y-015518X0220Y         S0      
317ETH10G_B1_RXP    J7    -D1   D0200PA00X-115764Y-016205X0320Y    R180 S3      
327ETH10G_B1_RXP    J5    -13         A01X-112028Y-014236X0200Y0790R180 S1      
317ETH10G_B1_RXN    VIA   -    MD0100PA00X-112345Y-015518X0220Y         S0      
317ETH10G_B1_RXN    J7    -E1   D0200PA00X-115764Y-015654X0320Y    R180 S3      
327ETH10G_B1_RXN    J5    -12         A01X-112343Y-014236X0200Y0790R180 S1      
317ETH10G_B1_RS1    VIA   -    MD0100PA00X-112500Y-010170X0220Y         S0      
317ETH10G_B1_RS1    VIA   -    M      A01X-117895Y-002325X0220Y         S2      
017ETH10G_B1_RS1    VIA   -    M      A08X-117895Y-002325X0320Y         S2      
017ETH10G_B1_RS1          -    MD0100PA00X-117895Y-002325                       
327ETH10G_B1_RS1    R25   -1          A01X-118237Y-001825X0280Y0320R180 S1      
327ETH10G_B1_RS1    R24   -2   M      A01X-118237Y-002345X0280Y0320R180 S1      
327ETH10G_B1_RS1    J5    -9          A01X-112500Y-011008X0200Y0790R180 S1      
317ETH10G_B1_RS0    VIA   -    MD0100PA00X-111870Y-010176X0220Y         S0      
317ETH10G_B1_RS0    VIA   -    M      A01X-116015Y-002675X0220Y         S2      
017ETH10G_B1_RS0    VIA   -    M      A08X-116015Y-002675X0320Y         S2      
017ETH10G_B1_RS0          -    MD0100PA00X-116015Y-002675                       
327ETH10G_B1_RS0    R23   -1          A01X-116337Y-002175X0280Y0320R180 S1      
327ETH10G_B1_RS0    R22   -2          A01X-116337Y-002695X0280Y0320R180 S1      
327ETH10G_B1_RS0    J5    -7          A01X-111870Y-011008X0200Y0790R180 S1      
317m0190            J7    -I2   D0200PA00X-116551Y-013488X0320Y    R180 S3      
327m0190            R15   -1          A01X-118736Y-000580X0280Y0320     S1      
317m0190            VIA   -    MD0100PA00X-119236Y-000580X0220Y         S0      
317m0191            VIA   -    M      A01X-111549Y-010424X0220Y         S2      
017m0191            VIA   -    M      A08X-111549Y-010424X0320Y         S2      
017m0191                  -    MD0100PA00X-111549Y-010424                       
327m0191            R29   -1          A01X-118224Y+000000X0280Y0320R180 S1      
327m0191            R15   -2   M      A01X-118224Y-000580X0280Y0320R180 S1      
317m0191            VIA   -    MD0100PA00X-117880Y-000580X0220Y         S0      
327m0191            J5    -6          A01X-111555Y-011008X0200Y0790R180 S1      
327m0192            J14   -136        A01X-058911Y-008939X0250Y    R090 S1      
317m0192            VIA   -    MD0100PA00X-059161Y-008689X0220Y         S0      
317m0192            J13   -J9   D0200PA00X-073803Y-012858X0320Y    R180 S3      
327m0193            J14   -134        A01X-059911Y-008939X0250Y    R090 S1      
317m0193            VIA   -    MD0100PA00X-060161Y-008689X0220Y         S0      
317m0193            J13   -G9   D0200PA00X-073803Y-014512X0320Y    R180 S3      
327m0194            J14   -132        A01X-060911Y-008939X0250Y    R090 S1      
317m0194            VIA   -    MD0100PA00X-061161Y-008689X0220Y         S0      
317m0194            J13   -D9   D0200PA00X-073803Y-016165X0320Y    R180 S3      
327m0195            J14   -130        A01X-061911Y-008939X0250Y    R090 S1      
317m0195            J13   -A9   D0200PA00X-073803Y-017819X0320Y    R180 S3      
327m0196            J14   -144        A01X-058911Y-008439X0250Y    R090 S1      
317m0196            VIA   -    MD0100PA00X-059161Y-008189X0220Y         S0      
317m0196            J13   -K9   D0200PA00X-073803Y-012307X0320Y    R180 S3      
327m0197            J14   -142        A01X-059911Y-008439X0250Y    R090 S1      
317m0197            VIA   -    MD0100PA00X-060161Y-008189X0220Y         S0      
317m0197            J13   -H9   D0200PA00X-073803Y-013961X0320Y    R180 S3      
327m0198            J14   -140        A01X-060911Y-008439X0250Y    R090 S1      
317m0198            VIA   -    MD0100PA00X-061161Y-008189X0220Y         S0      
317m0198            J13   -E9   D0200PA00X-073803Y-015614X0320Y    R180 S3      
327m0199            J14   -138        A01X-061911Y-008439X0250Y    R090 S1      
317m0199            J13   -B9   D0200PA00X-073803Y-017268X0320Y    R180 S3      
317m0200            VIA   -    MD0100PA00X-146169Y-008689X0220Y         S0      
327m0200            J2    -136        A01X-145919Y-008939X0250Y    R090 S1      
317m0200            J1    -J9   D0200PA00X-160811Y-012858X0320Y    R180 S3      
317m0201            VIA   -    MD0100PA00X-147169Y-008689X0220Y         S0      
327m0201            J2    -134        A01X-146919Y-008939X0250Y    R090 S1      
317m0201            J1    -G9   D0200PA00X-160811Y-014512X0320Y    R180 S3      
317m0202            J1    -D9   D0200PA00X-160811Y-016165X0320Y    R180 S3      
317m0202            VIA   -    MD0100PA00X-148169Y-008689X0220Y         S0      
327m0202            J2    -132        A01X-147919Y-008939X0250Y    R090 S1      
317m0203            J1    -A9   D0200PA00X-160811Y-017819X0320Y    R180 S3      
327m0203            J2    -130        A01X-148919Y-008939X0250Y    R090 S1      
317m0204            J1    -K9   D0200PA00X-160811Y-012307X0320Y    R180 S3      
317m0204            VIA   -    MD0100PA00X-146169Y-008189X0220Y         S0      
327m0204            J2    -144        A01X-145919Y-008439X0250Y    R090 S1      
317m0205            VIA   -    MD0100PA00X-147169Y-008189X0220Y         S0      
327m0205            J2    -142        A01X-146919Y-008439X0250Y    R090 S1      
317m0205            J1    -H9   D0200PA00X-160811Y-013961X0320Y    R180 S3      
317m0206            J1    -E9   D0200PA00X-160811Y-015614X0320Y    R180 S3      
317m0206            VIA   -    MD0100PA00X-148169Y-008189X0220Y         S0      
327m0206            J2    -140        A01X-147919Y-008439X0250Y    R090 S1      
327m0207            J2    -138        A01X-148919Y-008439X0250Y    R090 S1      
317m0207            J1    -B9   D0200PA00X-160811Y-017268X0320Y    R180 S3      
317m0208            J19   -I5   D0200PA00X-031906Y-013449X0320Y    R180 S3      
327m0208            R40   -1          A01X-031806Y-004200X0280Y0320     S1      
317m0208            VIA   -    MD0100PA00X-032170Y-004200X0220Y         S0      
317m0209            J7    -I5   D0200PA00X-118913Y-013449X0320Y    R180 S3      
327m0209            R12   -1          A01X-118756Y-004050X0280Y0320     S1      
317m0209            VIA   -    MD0100PA00X-119120Y-004050X0220Y         S0      
C                                                                               
C  ****************************************                                     
C      DUMMY NET PINS & VIAS ON THE BOARD                                       
C  ****************************************                                     
C                                                                               
317N/C              J13   -G7   D0200PA00X-072228Y-014512X0320Y    R180 S3      
317N/C              J1    -G7   D0200PA00X-159236Y-014512X0320Y    R180 S3      
317N/C              J19   -E2   D0200PA00X-029543Y-015693X0320Y    R180 S3      
317N/C              J7    -E2   D0200PA00X-116551Y-015693X0320Y    R180 S3      
317N/C              J24   -2D2  D0150PA00X-012441Y-009307X0270Y    R180 S3      
317N/C              J24   -2D1  D0150PA00X-012146Y-009858X0270Y    R180 S3      
317N/C              J24   -2C2  D0150PA00X-012441Y-007811X0270Y    R180 S3      
317N/C              J24   -2C1  D0150PA00X-012146Y-008362X0270Y    R180 S3      
317N/C              J24   -2B2  D0150PA00X-012441Y-006315X0270Y    R180 S3      
317N/C              J24   -2B1  D0150PA00X-012146Y-006866X0270Y    R180 S3      
317N/C              J24   -2A2  D0150PA00X-012441Y-004819X0270Y    R180 S3      
317N/C              J24   -2A1  D0150PA00X-012146Y-005370X0270Y    R180 S3      
317N/C              J24   -1D2  D0150PA00X-008110Y-009307X0270Y    R180 S3      
317N/C              J24   -1D1  D0150PA00X-007815Y-009858X0270Y    R180 S3      
317N/C              J24   -1C2  D0150PA00X-008110Y-007811X0270Y    R180 S3      
317N/C              J24   -1C1  D0150PA00X-007815Y-008362X0270Y    R180 S3      
317N/C              J24   -1B2  D0150PA00X-008110Y-006315X0270Y    R180 S3      
317N/C              J24   -1B1  D0150PA00X-007815Y-006866X0270Y    R180 S3      
317N/C              J24   -1A2  D0150PA00X-008110Y-004819X0270Y    R180 S3      
317N/C              J24   -1A1  D0150PA00X-007815Y-005370X0270Y    R180 S3      
317N/C              J12   -2D2  D0150PA00X-099449Y-009307X0270Y    R180 S3      
317N/C              J12   -2D1  D0150PA00X-099154Y-009858X0270Y    R180 S3      
317N/C              J12   -2C2  D0150PA00X-099449Y-007811X0270Y    R180 S3      
317N/C              J12   -2C1  D0150PA00X-099154Y-008362X0270Y    R180 S3      
317N/C              J12   -2B2  D0150PA00X-099449Y-006315X0270Y    R180 S3      
317N/C              J12   -2B1  D0150PA00X-099154Y-006866X0270Y    R180 S3      
317N/C              J12   -2A2  D0150PA00X-099449Y-004819X0270Y    R180 S3      
317N/C              J12   -2A1  D0150PA00X-099154Y-005370X0270Y    R180 S3      
317N/C              J12   -1D2  D0150PA00X-095118Y-009307X0270Y    R180 S3      
317N/C              J12   -1D1  D0150PA00X-094823Y-009858X0270Y    R180 S3      
317N/C              J12   -1C2  D0150PA00X-095118Y-007811X0270Y    R180 S3      
317N/C              J12   -1C1  D0150PA00X-094823Y-008362X0270Y    R180 S3      
317N/C              J12   -1B2  D0150PA00X-095118Y-006315X0270Y    R180 S3      
317N/C              J12   -1B1  D0150PA00X-094823Y-006866X0270Y    R180 S3      
317N/C              J12   -1A2  D0150PA00X-095118Y-004819X0270Y    R180 S3      
317N/C              J12   -1A1  D0150PA00X-094823Y-005370X0270Y    R180 S3      
C                                                                               
C  ****************************************                                     
C      TOOLING HOLE PINS ON THE BOARD                                           
C  ****************************************                                     
C                                                                               
367                       -     D0610UA00X-121201Y-014236X0500Y    R270 S3      
367                       -     D0610UA00X-127815Y-014236X0500Y    R270 S3      
367                       -     D0610UA00X-034193Y-014236X0500Y    R270 S3      
367                       -     D0610UA00X-040807Y-014236X0500Y    R270 S3      
367                       -     D0630UA00X-109429Y-012622X0500Y    R180 S3      
367                       -     D0630UA00X-113209Y-012622X0500Y    R180 S3      
367                       -     D0630UA00X-022421Y-012622X0500Y    R180 S3      
367                       -     D0630UA00X-026201Y-012622X0500Y    R180 S3      
367                       -     D0870PA00X-096004Y-003638X1500Y    R180 S3      
367                       -     D0870PA00X-100335Y-003638X1500Y    R180 S3      
367                       -     D0870PA00X-008996Y-003638X1500Y    R180 S3      
367                       -     D0870PA00X-013327Y-003638X1500Y    R180 S3      
367                       -     D0500UA00X-148869Y-017894X0200Y    R090 S3      
367                       -     D0500UA00X-147669Y-006484X0200Y    R090 S3      
367                       -     D0500UA00X-061861Y-017894X0200Y    R090 S3      
367                       -     D0500UA00X-060661Y-006484X0200Y    R090 S3      
367                       -     D1560UA00X-135689Y-011894X0500Y    R180 S3      
367                       -     D1560UA00X-135689Y-016717X0500Y    R180 S3      
367                       -     D1560UA00X-105161Y-011894X0500Y    R180 S3      
367                       -     D1560UA00X-105161Y-016717X0500Y    R180 S3      
367                       -     D1560UA00X-048681Y-011894X0500Y    R180 S3      
367                       -     D1560UA00X-048681Y-016717X0500Y    R180 S3      
367                       -     D1560UA00X-018153Y-011894X0500Y    R180 S3      
367                       -     D1560UA00X-018153Y-016717X0500Y    R180 S3      
367                       -     D0860UA00X-044193Y-014945X0500Y         S3      
367                       -     D0860UA00X-131201Y-014945X0500Y         S3      
367                       -     D1250UA00X-141000Y+000000X0500Y         S3      
367                       -     D1250UA00X+000000Y+000000X0500Y         S3      
367                       -     D1250UA00X+000000Y-013645X0500Y         S3      
C                                                                               
C  End-of-Job                                                                   
C                                                                               
999                                                                             
